FILE_TYPE = MACRO_DRAWING;
SET COLOR_WIRE YELLOW;
SET COLOR_PROP MONO;
SET COLOR_DOT WHITE;
SET COLOR_ARC YELLOW;
SET COLOR_BODY GREEN;
SET COLOR_NOTE MONO;
SET PROP_DISPLAY VALUE;
SET PAGE_NUMBER P218;
FORCEADD GND..1
(-1250 -250);
FORCEPROP 3 LASTPIN (-1250 -200) SIG_NAME GND\g
J 0
(-1240 -190);
DISPLAY 0.659574 (-1240 -190);
PAINT MONO (-1240 -190);
DISPLAY INVISIBLE (-1240 -190);
FORCEPROP 1 LAST PATH I1
J 0
(-1175 -250);
DISPLAY 0.872340 (-1175 -250);
PAINT AQUA (-1175 -250);
DISPLAY INVISIBLE (-1175 -250);
FORCEPROP 2 LAST ROOM VDDQ_DEF_PWR_VR
J 0
(-1825 -175);
DISPLAY 1.361702 (-1825 -175);
PAINT ORANGE (-1825 -175);
DISPLAY INVISIBLE (-1825 -175);
FORCEPROP 1 LAST BODY_TYPE PLUMBING
J 0
(-1295 -293);
DISPLAY 0.340426 (-1295 -293);
PAINT GREEN (-1295 -293);
DISPLAY INVISIBLE (-1295 -293);
FORCEPROP 2 LAST CDS_LIB mstr_symbols
J 0
(-1250 -250);
PAINT ORANGE (-1250 -250);
DISPLAY INVISIBLE (-1250 -250);
FORCEPROP 1 LAST VOLTAGE 0
J 0
(-1250 -250);
PAINT SKYBLUE (-1250 -250);
DISPLAY INVISIBLE (-1250 -250);
FORCEPROP 1 LAST HDL_POWER GND
J 0
(-1250 -100);
DISPLAY 1.170213 (-1250 -100);
PAINT GREEN (-1250 -100);
DISPLAY INVISIBLE (-1250 -100);
FORCEPROP 1 LAST SIZE 1B
J 0
(-1175 -300);
DISPLAY 1.170213 (-1175 -300);
PAINT AQUA (-1175 -300);
DISPLAY INVISIBLE (-1175 -300);
FORCEADD OFFPAGE..1
(-3525 2000);
FORCEPROP 2 LAST $XR0 219 
J 0
(-3777 2000);
DISPLAY 0.638298 (-3777 2000);
PAINT MONO (-3777 2000);
FORCEPROP 2 LAST PATH I10
J 0
(-3775 2050);
DISPLAY 1.021277 (-3775 2050);
PAINT ORANGE (-3775 2050);
DISPLAY INVISIBLE (-3775 2050);
FORCEPROP 1 LAST COMMENT_BODY TRUE
J 0
(-3400 1900);
DISPLAY 1.170213 (-3400 1900);
PAINT GREEN (-3400 1900);
DISPLAY INVISIBLE (-3400 1900);
FORCEPROP 2 LAST ROOM VDDQ_DEF_PWR_VR
J 0
(-4075 2075);
DISPLAY 1.361702 (-4075 2075);
PAINT ORANGE (-4075 2075);
DISPLAY INVISIBLE (-4075 2075);
FORCEPROP 2 LAST CDS_LIB mstr_standard
J 0
(-3525 2000);
PAINT ORANGE (-3525 2000);
DISPLAY INVISIBLE (-3525 2000);
FORCEPROP 1 LAST OFFPAGE TRUE
J 0
(-3200 1875);
DISPLAY 1.170213 (-3200 1875);
PAINT GREEN (-3200 1875);
DISPLAY INVISIBLE (-3200 1875);
FORCEADD OFFPAGE..1
(-3525 2050);
FORCEPROP 2 LAST $XR0 219 
J 0
(-3777 2050);
DISPLAY 0.638298 (-3777 2050);
PAINT MONO (-3777 2050);
FORCEPROP 2 LAST PATH I11
J 0
(-3775 2100);
DISPLAY 1.021277 (-3775 2100);
PAINT ORANGE (-3775 2100);
DISPLAY INVISIBLE (-3775 2100);
FORCEPROP 2 LAST ROOM VDDQ_DEF_PWR_VR
J 0
(-4075 2125);
DISPLAY 1.361702 (-4075 2125);
PAINT ORANGE (-4075 2125);
DISPLAY INVISIBLE (-4075 2125);
FORCEPROP 2 LAST CDS_LIB mstr_standard
J 0
(-3525 2050);
PAINT ORANGE (-3525 2050);
DISPLAY INVISIBLE (-3525 2050);
FORCEPROP 1 LAST COMMENT_BODY TRUE
J 0
(-3400 1950);
DISPLAY 1.170213 (-3400 1950);
PAINT GREEN (-3400 1950);
DISPLAY INVISIBLE (-3400 1950);
FORCEPROP 1 LAST OFFPAGE TRUE
J 0
(-3200 1925);
DISPLAY 1.170213 (-3200 1925);
PAINT GREEN (-3200 1925);
DISPLAY INVISIBLE (-3200 1925);
FORCEADD OFFPAGE..1
(-3550 2725);
FORCEPROP 2 LAST $XR2 215 
J 0
(-3891 2689);
DISPLAY 0.638298 (-3891 2689);
PAINT MONO (-3891 2689);
FORCEPROP 2 LAST $XR1 194 
J 0
(-3891 2725);
DISPLAY 0.638298 (-3891 2725);
PAINT MONO (-3891 2725);
FORCEPROP 2 LAST $XR0 21 
J 0
(-3771 2725);
DISPLAY 0.638298 (-3771 2725);
PAINT MONO (-3771 2725);
FORCEPROP 2 LAST PATH I12
J 0
(-3750 2775);
DISPLAY 1.021277 (-3750 2775);
PAINT ORANGE (-3750 2775);
DISPLAY INVISIBLE (-3750 2775);
FORCEPROP 2 LAST ROOM VDDQ_DEF_PWR_VR
J 0
(-4100 2800);
DISPLAY 1.361702 (-4100 2800);
PAINT ORANGE (-4100 2800);
DISPLAY INVISIBLE (-4100 2800);
FORCEPROP 2 LAST CDS_LIB mstr_standard
J 0
(-3550 2725);
PAINT ORANGE (-3550 2725);
DISPLAY INVISIBLE (-3550 2725);
FORCEPROP 1 LAST COMMENT_BODY TRUE
J 0
(-3425 2625);
DISPLAY 1.170213 (-3425 2625);
PAINT GREEN (-3425 2625);
DISPLAY INVISIBLE (-3425 2625);
FORCEPROP 1 LAST OFFPAGE TRUE
J 0
(-3225 2600);
DISPLAY 1.170213 (-3225 2600);
PAINT GREEN (-3225 2600);
DISPLAY INVISIBLE (-3225 2600);
FORCEADD RES..1
(-2925 875);
FORCEPROP 1 LAST PART_NUMBER G21796-066
J 0
(-3075 825);
DISPLAY 0.617021 (-3075 825);
PAINT BLUE (-3075 825);
FORCEPROP 1 LAST VALUE 10.0
J 2
(-3025 775);
DISPLAY 0.617021 (-3025 775);
PAINT SKYBLUE (-3025 775);
FORCEPROP 1 LAST WATTAGE 1/16W
J 2
(-2925 725);
DISPLAY 0.617021 (-2925 725);
PAINT SKYBLUE (-2925 725);
FORCEPROP 1 LAST MATERIAL CHIP
J 0
(-2900 725);
DISPLAY 0.617021 (-2900 725);
PAINT SKYBLUE (-2900 725);
FORCEPROP 1 LAST PACK_TYPE 0402
J 0
(-2900 775);
DISPLAY 0.617021 (-2900 775);
PAINT SKYBLUE (-2900 775);
FORCEPROP 1 LASTPIN (-3025 875) $PN 1
J 0
(-3013 887);
DISPLAY 0.617021 (-3013 887);
PAINT ORANGE (-3013 887);
FORCEPROP 1 LAST TOLERANCE 1%
J 0
(-3000 775);
DISPLAY 0.617021 (-3000 775);
PAINT SKYBLUE (-3000 775);
FORCEPROP 1 LASTPIN (-2825 875) $PN 2
J 0
(-2863 887);
DISPLAY 0.617021 (-2863 887);
PAINT ORANGE (-2863 887);
FORCEPROP 1 LAST LOCATION R7A7
J 0
(-2975 925);
DISPLAY 0.617021 (-2975 925);
PAINT AQUA (-2975 925);
FORCEPROP 1 LAST PATH I13
J 0
(-2975 1025);
DISPLAY 0.978723 (-2975 1025);
PAINT WHITE (-2975 1025);
DISPLAY INVISIBLE (-2975 1025);
FORCEPROP 0 LAST CDS_SEC 1
J 0
(-2975 975);
PAINT MONO (-2975 975);
DISPLAY INVISIBLE (-2975 975);
FORCEPROP 2 LAST CDS_LIB mstr_discrete
J 0
(-2925 875);
PAINT ORANGE (-2925 875);
DISPLAY INVISIBLE (-2925 875);
FORCEPROP 2 LAST CDS_LOCATION R7A7
J 0
(-2975 925);
DISPLAY 0.617021 (-2975 925);
PAINT AQUA (-2975 925);
DISPLAY INVISIBLE (-2975 925);
FORCEPROP 2 LAST SEC_TYPE 0402
J 0
(-2975 1100);
DISPLAY 1.021277 (-2975 1100);
PAINT ORANGE (-2975 1100);
DISPLAY INVISIBLE (-2975 1100);
FORCEPROP 2 LAST SEC 1
J 0
(-2975 1100);
DISPLAY 0.680851 (-2975 1100);
PAINT MONO (-2975 1100);
DISPLAY INVISIBLE (-2975 1100);
FORCEPROP 2 LAST ROOM VDDQ_DEF_PWR_VR
J 0
(-2850 975);
DISPLAY 1.361702 (-2850 975);
PAINT ORANGE (-2850 975);
DISPLAY INVISIBLE (-2850 975);
FORCEADD CAP..1
(-2650 725);
FORCEPROP 1 LASTPIN (-2650 625) $PN 2
J 0
(-2640 605);
DISPLAY 0.617021 (-2640 605);
PAINT ORANGE (-2640 605);
FORCEPROP 1 LAST PACK_TYPE 0402LF
J 0
(-2600 625);
DISPLAY 0.617021 (-2600 625);
PAINT SKYBLUE (-2600 625);
FORCEPROP 1 LAST PART_NUMBER A36096-050
J 0
(-2600 675);
DISPLAY 0.617021 (-2600 675);
PAINT BLUE (-2600 675);
FORCEPROP 1 LAST VOLTAGE 50V
J 0
(-2600 725);
DISPLAY 0.617021 (-2600 725);
PAINT SKYBLUE (-2600 725);
FORCEPROP 1 LAST MATERIAL X7R
J 0
(-2475 725);
DISPLAY 0.617021 (-2475 725);
PAINT SKYBLUE (-2475 725);
FORCEPROP 1 LAST VALUE 220PF
J 0
(-2600 775);
DISPLAY 0.617021 (-2600 775);
PAINT SKYBLUE (-2600 775);
FORCEPROP 1 LAST LOCATION C7A28
J 0
(-2600 825);
DISPLAY 0.617021 (-2600 825);
PAINT AQUA (-2600 825);
FORCEPROP 1 LAST TOLERANCE 10%
J 0
(-2425 775);
DISPLAY 0.617021 (-2425 775);
PAINT SKYBLUE (-2425 775);
FORCEPROP 1 LASTPIN (-2650 825) $PN 1
J 0
(-2640 805);
DISPLAY 0.617021 (-2640 805);
PAINT ORANGE (-2640 805);
FORCEPROP 1 LAST PATH I14
J 0
(-2600 875);
DISPLAY 0.978723 (-2600 875);
PAINT WHITE (-2600 875);
DISPLAY INVISIBLE (-2600 875);
FORCEPROP 0 LAST CDS_SEC 1
J 0
(-2600 875);
PAINT MONO (-2600 875);
DISPLAY INVISIBLE (-2600 875);
FORCEPROP 2 LAST CDS_LIB mstr_discrete
J 0
(-2650 725);
PAINT ORANGE (-2650 725);
DISPLAY INVISIBLE (-2650 725);
FORCEPROP 2 LAST CDS_LOCATION C7A28
J 0
(-2600 825);
DISPLAY 0.617021 (-2600 825);
PAINT AQUA (-2600 825);
DISPLAY INVISIBLE (-2600 825);
FORCEPROP 2 LAST ROOM VDDQ_DEF_PWR_VR
J 0
(-2600 875);
DISPLAY 1.361702 (-2600 875);
PAINT ORANGE (-2600 875);
DISPLAY INVISIBLE (-2600 875);
FORCEPROP 2 LAST SEC 1
J 0
(-2600 950);
DISPLAY 0.680851 (-2600 950);
PAINT MONO (-2600 950);
DISPLAY INVISIBLE (-2600 950);
FORCEPROP 2 LAST SEC_TYPE 0402LF
J 0
(-2600 950);
DISPLAY 1.021277 (-2600 950);
PAINT ORANGE (-2600 950);
DISPLAY INVISIBLE (-2600 950);
FORCEADD RES..1
(-2900 1200);
FORCEPROP 1 LAST PACK_TYPE 0402
J 0
(-2825 1100);
DISPLAY 0.617021 (-2825 1100);
PAINT SKYBLUE (-2825 1100);
FORCEPROP 1 LAST TOLERANCE 5%
J 0
(-2950 1100);
DISPLAY 0.617021 (-2950 1100);
PAINT SKYBLUE (-2950 1100);
FORCEPROP 1 LAST WATTAGE 1/16W
J 2
(-2925 1050);
DISPLAY 0.617021 (-2925 1050);
PAINT SKYBLUE (-2925 1050);
FORCEPROP 1 LAST VALUE 0.0
J 2
(-3000 1100);
DISPLAY 0.617021 (-3000 1100);
PAINT SKYBLUE (-3000 1100);
FORCEPROP 1 LAST PART_NUMBER G21497-005
J 0
(-3050 1150);
DISPLAY 0.617021 (-3050 1150);
PAINT BLUE (-3050 1150);
FORCEPROP 1 LASTPIN (-3000 1200) $PN 1
J 0
(-2988 1212);
DISPLAY 0.787234 (-2988 1212);
PAINT ORANGE (-2988 1212);
FORCEPROP 1 LAST LOCATION R3M6
J 0
(-2950 1250);
DISPLAY 0.617021 (-2950 1250);
PAINT AQUA (-2950 1250);
FORCEPROP 1 LASTPIN (-2800 1200) $PN 2
J 0
(-2838 1212);
DISPLAY 0.787234 (-2838 1212);
PAINT ORANGE (-2838 1212);
FORCEPROP 1 LAST MATERIAL CHIP
J 0
(-2900 1050);
DISPLAY 0.617021 (-2900 1050);
PAINT SKYBLUE (-2900 1050);
FORCEPROP 1 LAST PATH I15
J 0
(-2950 1350);
DISPLAY 0.978723 (-2950 1350);
PAINT WHITE (-2950 1350);
DISPLAY INVISIBLE (-2950 1350);
FORCEPROP 0 LAST CDS_SEC 1
J 0
(-2950 1300);
PAINT MONO (-2950 1300);
DISPLAY INVISIBLE (-2950 1300);
FORCEPROP 2 LAST ROOM VDDQ_DEF_PWR_VR
J 0
(-2950 1300);
DISPLAY 1.361702 (-2950 1300);
PAINT ORANGE (-2950 1300);
DISPLAY INVISIBLE (-2950 1300);
FORCEPROP 2 LAST CDS_LOCATION R3M6
J 0
(-2950 1250);
DISPLAY 0.617021 (-2950 1250);
PAINT AQUA (-2950 1250);
DISPLAY INVISIBLE (-2950 1250);
FORCEPROP 2 LAST CDS_LIB mstr_discrete
J 0
(-2900 1200);
PAINT ORANGE (-2900 1200);
DISPLAY INVISIBLE (-2900 1200);
FORCEPROP 2 LAST SEC 1
J 0
(-2950 1400);
PAINT MONO (-2950 1400);
DISPLAY INVISIBLE (-2950 1400);
FORCEPROP 2 LAST SEC_TYPE 0402
J 0
(-2950 1400);
DISPLAY 1.021277 (-2950 1400);
PAINT ORANGE (-2950 1400);
DISPLAY INVISIBLE (-2950 1400);
FORCEADD CAP..1
R 2
(-1250 450);
FORCEPROP 1 LAST LOCATION C7A29
J 2
(-1300 550);
DISPLAY 0.617021 (-1300 550);
PAINT AQUA (-1300 550);
FORCEPROP 1 LAST PART_NUMBER A36096-050
J 2
(-1300 400);
DISPLAY 0.617021 (-1300 400);
PAINT BLUE (-1300 400);
FORCEPROP 1 LAST MATERIAL X7R
J 2
(-1425 450);
DISPLAY 0.617021 (-1425 450);
PAINT SKYBLUE (-1425 450);
FORCEPROP 1 LAST PACK_TYPE 0402LF
J 2
(-1300 350);
DISPLAY 0.617021 (-1300 350);
PAINT SKYBLUE (-1300 350);
FORCEPROP 1 LAST VOLTAGE 50V
J 2
(-1300 450);
DISPLAY 0.617021 (-1300 450);
PAINT SKYBLUE (-1300 450);
FORCEPROP 1 LAST TOLERANCE 10%
J 2
(-1475 500);
DISPLAY 0.617021 (-1475 500);
PAINT SKYBLUE (-1475 500);
FORCEPROP 1 LAST VALUE 220PF
J 2
(-1300 500);
DISPLAY 0.617021 (-1300 500);
PAINT SKYBLUE (-1300 500);
FORCEPROP 1 LASTPIN (-1250 550) $PN 1
J 2
(-1260 530);
DISPLAY 0.617021 (-1260 530);
PAINT ORANGE (-1260 530);
FORCEPROP 1 LASTPIN (-1250 350) $PN 2
J 2
(-1260 330);
DISPLAY 0.617021 (-1260 330);
PAINT ORANGE (-1260 330);
FORCEPROP 1 LAST PATH I16
J 2
(-1300 600);
DISPLAY 0.978723 (-1300 600);
PAINT WHITE (-1300 600);
DISPLAY INVISIBLE (-1300 600);
FORCEPROP 0 LAST CDS_SEC 1
J 0
(-1300 600);
PAINT MONO (-1300 600);
DISPLAY INVISIBLE (-1300 600);
FORCEPROP 2 LAST SEC_TYPE 0402LF
J 2
(-1300 675);
DISPLAY 1.021277 (-1300 675);
PAINT ORANGE (-1300 675);
DISPLAY INVISIBLE (-1300 675);
FORCEPROP 2 LAST CDS_LIB mstr_discrete
J 2
(-1250 450);
PAINT ORANGE (-1250 450);
DISPLAY INVISIBLE (-1250 450);
FORCEPROP 2 LAST ROOM VDDQ_DEF_PWR_VR
J 2
(-1300 600);
DISPLAY 1.361702 (-1300 600);
PAINT ORANGE (-1300 600);
DISPLAY INVISIBLE (-1300 600);
FORCEPROP 2 LAST CDS_LOCATION C7A29
J 2
(-1300 550);
DISPLAY 0.617021 (-1300 550);
PAINT AQUA (-1300 550);
DISPLAY INVISIBLE (-1300 550);
FORCEPROP 2 LAST SEC 1
J 2
(-1300 675);
DISPLAY 0.680851 (-1300 675);
PAINT MONO (-1300 675);
DISPLAY INVISIBLE (-1300 675);
FORCEADD SC22P50V2JN-4GP..1
R 1
(-2200 2250);
FORCEPROP 0 LAST GROUP POWER_FAIR
J 0
(-2313 2180);
DISPLAY 0.638298 (-2313 2180);
PAINT BROWN (-2313 2180);
DISPLAY BOTH (-2313 2180);
FORCEPROP 1 LAST VALUE SC22P50V2JN-4GP
J 0
(-2325 2125);
DISPLAY 0.617021 (-2325 2125);
PAINT GREEN (-2325 2125);
FORCEPROP 2 LAST PACK_SIZE 0402
J 0
(-2000 2075);
DISPLAY 0.638298 (-2000 2075);
PAINT GREEN (-2000 2075);
FORCEPROP 2 LAST RATED 50V
J 0
(-2225 2075);
DISPLAY 0.638298 (-2225 2075);
PAINT GREEN (-2225 2075);
FORCEPROP 2 LAST TYPE NPO
J 0
(-2125 2075);
DISPLAY 0.638298 (-2125 2075);
PAINT GREEN (-2125 2075);
FORCEPROP 2 LAST ATTRIBUTE 22PF
J 0
(-2450 2075);
DISPLAY 0.638298 (-2450 2075);
PAINT GREEN (-2450 2075);
FORCEPROP 2 LAST TOLERANCE 5%
J 0
(-2325 2075);
DISPLAY 0.638298 (-2325 2075);
PAINT GREEN (-2325 2075);
FORCEPROP 0 LASTPIN (-2275 2250) $PN 1
J 2
(-2285 2260);
DISPLAY 0.808511 (-2285 2260);
PAINT MONO (-2285 2260);
FORCEPROP 1 LAST LOCATION CF17
J 0
(-2455 2125);
DISPLAY 0.617021 (-2455 2125);
PAINT GREEN (-2455 2125);
FORCEPROP 0 LASTPIN (-2125 2250) $PN 2
J 0
(-2115 2260);
DISPLAY 0.808511 (-2115 2260);
PAINT MONO (-2115 2260);
FORCEPROP 1 LAST CDS_LMAN_SYM_OUTLINE -50,25,50,-25
R 1
J 0
(-2200 2250);
DISPLAY 0.468085 (-2200 2250);
PAINT GREEN (-2200 2250);
DISPLAY INVISIBLE (-2200 2250);
FORCEPROP 2 LAST CDS_LIB w_hdl
J 0
(-2200 2250);
PAINT MONO (-2200 2250);
DISPLAY INVISIBLE (-2200 2250);
FORCEPROP 1 LAST PART_NUMBER 78.22034.1FL
R 1
J 0
(-2200 2250);
DISPLAY 0.617021 (-2200 2250);
PAINT GREEN (-2200 2250);
DISPLAY INVISIBLE (-2200 2250);
FORCEPROP 1 LAST PACK_TYPE SMD-BCG
R 1
J 0
(-2200 2250);
DISPLAY 0.617021 (-2200 2250);
PAINT GREEN (-2200 2250);
DISPLAY INVISIBLE (-2200 2250);
FORCEPROP 0 LAST CDS_LOCATION CF17
R 1
J 0
(-2200 2350);
PAINT MONO (-2200 2350);
DISPLAY INVISIBLE (-2200 2350);
FORCEPROP 0 LAST $SEC 1
R 1
J 0
(-2200 2350);
PAINT MONO (-2200 2350);
DISPLAY INVISIBLE (-2200 2350);
FORCEPROP 0 LAST CDS_SEC 1
R 1
J 0
(-2200 2350);
PAINT MONO (-2200 2350);
DISPLAY INVISIBLE (-2200 2350);
FORCEPROP 1 LAST PATH I17
R 1
J 0
(-2200 2250);
DISPLAY 0.617021 (-2200 2250);
PAINT GREEN (-2200 2250);
DISPLAY INVISIBLE (-2200 2250);
FORCEADD RES..1
(-2200 2400);
FORCEPROP 0 LAST GROUP POWER_FAIR
J 0
(-2400 2350);
DISPLAY 0.638298 (-2400 2350);
PAINT BROWN (-2400 2350);
DISPLAY BOTH (-2400 2350);
FORCEPROP 0 LAST FAIR_SS 064.9530D.M001
J 0
(-2400 2300);
DISPLAY 0.638298 (-2400 2300);
PAINT BROWN (-2400 2300);
DISPLAY BOTH (-2400 2300);
FORCEPROP 1 LASTPIN (-2300 2400) $PN 1
J 0
(-2288 2412);
DISPLAY 0.787234 (-2288 2412);
PAINT ORANGE (-2288 2412);
FORCEPROP 1 LAST PACK_TYPE 0402
J 0
(-2250 2450);
DISPLAY 0.617021 (-2250 2450);
PAINT SKYBLUE (-2250 2450);
FORCEPROP 1 LAST PART_NUMBER G85996-004
J 0
(-2475 2450);
DISPLAY 0.617021 (-2475 2450);
PAINT BLUE (-2475 2450);
FORCEPROP 1 LAST LOCATION RF17
J 0
(-2475 2500);
DISPLAY 0.617021 (-2475 2500);
PAINT AQUA (-2475 2500);
FORCEPROP 1 LAST VALUE 1.0K
J 2
(-2275 2500);
DISPLAY 0.617021 (-2275 2500);
PAINT SKYBLUE (-2275 2500);
FORCEPROP 1 LAST TOLERANCE 0.1%
J 0
(-2250 2500);
DISPLAY 0.617021 (-2250 2500);
PAINT SKYBLUE (-2250 2500);
FORCEPROP 1 LASTPIN (-2100 2400) $PN 2
J 0
(-2138 2412);
DISPLAY 0.787234 (-2138 2412);
PAINT ORANGE (-2138 2412);
FORCEPROP 1 LAST MATERIAL CHIP
J 0
(-2125 2450);
DISPLAY 0.617021 (-2125 2450);
PAINT SKYBLUE (-2125 2450);
FORCEPROP 1 LAST WATTAGE 1/16W
J 2
(-2025 2500);
DISPLAY 0.617021 (-2025 2500);
PAINT SKYBLUE (-2025 2500);
FORCEPROP 1 LAST PATH I18
J 0
(-2250 2550);
DISPLAY 0.978723 (-2250 2550);
PAINT WHITE (-2250 2550);
DISPLAY INVISIBLE (-2250 2550);
FORCEPROP 0 LAST CDS_LOCATION RF17
J 0
(-2125 2550);
PAINT MONO (-2125 2550);
DISPLAY INVISIBLE (-2125 2550);
FORCEPROP 2 LAST CDS_LIB mstr_discrete
J 0
(-2200 2400);
PAINT MONO (-2200 2400);
DISPLAY INVISIBLE (-2200 2400);
FORCEPROP 0 LAST ROOM SB
J 0
(-2150 2625);
DISPLAY 1.021277 (-2150 2625);
PAINT ORANGE (-2150 2625);
DISPLAY INVISIBLE (-2150 2625);
FORCEPROP 2 LAST SEC_TYPE 0402
J 0
(-2250 2600);
DISPLAY 1.021277 (-2250 2600);
PAINT ORANGE (-2250 2600);
DISPLAY INVISIBLE (-2250 2600);
FORCEPROP 0 LAST SEC 1
J 0
(-2125 2550);
PAINT MONO (-2125 2550);
DISPLAY INVISIBLE (-2125 2550);
FORCEADD RES..1
(-1550 2400);
FORCEPROP 1 LAST VALUE 1.0K
J 2
(-1600 2500);
DISPLAY 0.617021 (-1600 2500);
PAINT SKYBLUE (-1600 2500);
FORCEPROP 1 LAST LOCATION RF18
J 0
(-1800 2500);
DISPLAY 0.617021 (-1800 2500);
PAINT AQUA (-1800 2500);
FORCEPROP 1 LASTPIN (-1650 2400) $PN 1
J 0
(-1638 2412);
DISPLAY 0.787234 (-1638 2412);
PAINT ORANGE (-1638 2412);
FORCEPROP 1 LAST TOLERANCE 0.1%
J 0
(-1575 2500);
DISPLAY 0.617021 (-1575 2500);
PAINT SKYBLUE (-1575 2500);
FORCEPROP 1 LAST PART_NUMBER G85996-004
J 0
(-1800 2450);
DISPLAY 0.617021 (-1800 2450);
PAINT BLUE (-1800 2450);
FORCEPROP 1 LAST MATERIAL CHIP
J 0
(-1425 2450);
DISPLAY 0.617021 (-1425 2450);
PAINT SKYBLUE (-1425 2450);
FORCEPROP 1 LAST WATTAGE 1/16W
J 2
(-1350 2500);
DISPLAY 0.617021 (-1350 2500);
PAINT SKYBLUE (-1350 2500);
FORCEPROP 1 LAST PACK_TYPE 0402
J 0
(-1550 2450);
DISPLAY 0.617021 (-1550 2450);
PAINT SKYBLUE (-1550 2450);
FORCEPROP 1 LASTPIN (-1450 2400) $PN 2
J 0
(-1488 2412);
DISPLAY 0.787234 (-1488 2412);
PAINT ORANGE (-1488 2412);
FORCEPROP 0 LAST BOM_SS NOPOP
J 0
(-1750 2300);
DISPLAY 0.638298 (-1750 2300);
PAINT BROWN (-1750 2300);
DISPLAY BOTH (-1750 2300);
FORCEPROP 0 LAST GROUP POWER_FAIR
J 0
(-1750 2350);
DISPLAY 0.638298 (-1750 2350);
PAINT BROWN (-1750 2350);
DISPLAY BOTH (-1750 2350);
FORCEPROP 2 LAST CDS_LIB mstr_discrete
J 0
(-1550 2400);
PAINT MONO (-1550 2400);
DISPLAY INVISIBLE (-1550 2400);
FORCEPROP 0 LAST ROOM SB
J 0
(-1500 2625);
DISPLAY 1.021277 (-1500 2625);
PAINT ORANGE (-1500 2625);
DISPLAY INVISIBLE (-1500 2625);
FORCEPROP 0 LAST CDS_LOCATION RF18
J 0
(-1475 2550);
PAINT MONO (-1475 2550);
DISPLAY INVISIBLE (-1475 2550);
FORCEPROP 1 LAST PATH I19
J 0
(-1600 2550);
DISPLAY 0.978723 (-1600 2550);
PAINT WHITE (-1600 2550);
DISPLAY INVISIBLE (-1600 2550);
FORCEPROP 2 LAST SEC_TYPE 0402
J 0
(-1600 2600);
DISPLAY 1.021277 (-1600 2600);
PAINT ORANGE (-1600 2600);
DISPLAY INVISIBLE (-1600 2600);
FORCEPROP 0 LAST SEC 1
J 0
(-1475 2550);
PAINT MONO (-1475 2550);
DISPLAY INVISIBLE (-1475 2550);
FORCEADD OFFPAGE..1
(-3525 600);
FORCEPROP 2 LAST $XR0 220 
J 0
(-3777 600);
DISPLAY 0.638298 (-3777 600);
PAINT MONO (-3777 600);
FORCEPROP 2 LAST PATH I2
J 0
(-3775 650);
DISPLAY 1.021277 (-3775 650);
PAINT ORANGE (-3775 650);
DISPLAY INVISIBLE (-3775 650);
FORCEPROP 2 LAST ROOM VDDQ_DEF_PWR_VR
J 0
(-4075 675);
DISPLAY 1.361702 (-4075 675);
PAINT ORANGE (-4075 675);
DISPLAY INVISIBLE (-4075 675);
FORCEPROP 2 LAST CDS_LIB mstr_standard
J 0
(-3525 600);
PAINT ORANGE (-3525 600);
DISPLAY INVISIBLE (-3525 600);
FORCEPROP 1 LAST COMMENT_BODY TRUE
J 0
(-3400 500);
DISPLAY 1.170213 (-3400 500);
PAINT GREEN (-3400 500);
DISPLAY INVISIBLE (-3400 500);
FORCEPROP 1 LAST OFFPAGE TRUE
J 0
(-3200 475);
DISPLAY 1.170213 (-3200 475);
PAINT GREEN (-3200 475);
DISPLAY INVISIBLE (-3200 475);
FORCEADD SC22P50V2JN-4GP..1
R 1
(-1550 2250);
FORCEPROP 0 LAST BOM_SS NOPOP
J 0
(-1750 2125);
DISPLAY 0.638298 (-1750 2125);
PAINT BROWN (-1750 2125);
DISPLAY BOTH (-1750 2125);
FORCEPROP 1 LAST LOCATION CF18
J 0
(-1755 2075);
DISPLAY 0.617021 (-1755 2075);
PAINT GREEN (-1755 2075);
FORCEPROP 2 LAST ATTRIBUTE 22PF
J 0
(-1750 2025);
DISPLAY 0.638298 (-1750 2025);
PAINT GREEN (-1750 2025);
FORCEPROP 2 LAST TOLERANCE 5%
J 0
(-1625 2025);
DISPLAY 0.638298 (-1625 2025);
PAINT GREEN (-1625 2025);
FORCEPROP 2 LAST RATED 50V
J 0
(-1525 2025);
DISPLAY 0.638298 (-1525 2025);
PAINT GREEN (-1525 2025);
FORCEPROP 2 LAST TYPE NPO
J 0
(-1425 2025);
DISPLAY 0.638298 (-1425 2025);
PAINT GREEN (-1425 2025);
FORCEPROP 0 LASTPIN (-1625 2250) $PN 1
J 2
(-1635 2260);
DISPLAY 0.808511 (-1635 2260);
PAINT MONO (-1635 2260);
FORCEPROP 0 LASTPIN (-1475 2250) $PN 2
J 0
(-1465 2260);
DISPLAY 0.808511 (-1465 2260);
PAINT MONO (-1465 2260);
FORCEPROP 2 LAST PACK_SIZE 0402
J 0
(-1325 2025);
DISPLAY 0.638298 (-1325 2025);
PAINT GREEN (-1325 2025);
FORCEPROP 1 LAST VALUE SC22P50V2JN-4GP
J 0
(-1625 2075);
DISPLAY 0.617021 (-1625 2075);
PAINT GREEN (-1625 2075);
FORCEPROP 0 LAST GROUP POWER_FAIR
J 0
(-1763 2180);
DISPLAY 0.638298 (-1763 2180);
PAINT BROWN (-1763 2180);
DISPLAY BOTH (-1763 2180);
FORCEPROP 1 LAST PART_NUMBER 78.22034.1FL
R 1
J 0
(-1550 2250);
DISPLAY 0.617021 (-1550 2250);
PAINT GREEN (-1550 2250);
DISPLAY INVISIBLE (-1550 2250);
FORCEPROP 1 LAST PACK_TYPE SMD-BCG
R 1
J 0
(-1550 2250);
DISPLAY 0.617021 (-1550 2250);
PAINT GREEN (-1550 2250);
DISPLAY INVISIBLE (-1550 2250);
FORCEPROP 1 LAST CDS_LMAN_SYM_OUTLINE -50,25,50,-25
R 1
J 0
(-1550 2250);
DISPLAY 0.468085 (-1550 2250);
PAINT GREEN (-1550 2250);
DISPLAY INVISIBLE (-1550 2250);
FORCEPROP 2 LAST CDS_LIB w_hdl
J 0
(-1550 2250);
PAINT MONO (-1550 2250);
DISPLAY INVISIBLE (-1550 2250);
FORCEPROP 0 LAST CDS_LOCATION CF18
R 1
J 0
(-1700 2350);
PAINT MONO (-1700 2350);
DISPLAY INVISIBLE (-1700 2350);
FORCEPROP 0 LAST $SEC 1
R 1
J 0
(-1700 2350);
PAINT MONO (-1700 2350);
DISPLAY INVISIBLE (-1700 2350);
FORCEPROP 0 LAST CDS_SEC 1
R 1
J 0
(-1700 2350);
PAINT MONO (-1700 2350);
DISPLAY INVISIBLE (-1700 2350);
FORCEPROP 1 LAST PATH I20
R 1
J 0
(-1550 2250);
DISPLAY 0.617021 (-1550 2250);
PAINT GREEN (-1550 2250);
DISPLAY INVISIBLE (-1550 2250);
FORCEADD RES..1
(-1475 2725);
FORCEPROP 1 LAST TOLERANCE 1%
J 0
(-1425 2800);
DISPLAY 0.617021 (-1425 2800);
PAINT SKYBLUE (-1425 2800);
FORCEPROP 1 LAST WATTAGE 1/16W
J 2
(-1425 2750);
DISPLAY 0.617021 (-1425 2750);
PAINT SKYBLUE (-1425 2750);
FORCEPROP 1 LASTPIN (-1375 2725) $PN 2
J 0
(-1413 2737);
DISPLAY 0.617021 (-1413 2737);
PAINT ORANGE (-1413 2737);
FORCEPROP 1 LAST PACK_TYPE 0402
J 0
(-1300 2800);
DISPLAY 0.617021 (-1300 2800);
PAINT SKYBLUE (-1300 2800);
FORCEPROP 1 LASTPIN (-1575 2725) $PN 1
J 0
(-1563 2737);
DISPLAY 0.617021 (-1563 2737);
PAINT ORANGE (-1563 2737);
FORCEPROP 1 LAST MATERIAL CHIP
J 0
(-1375 2750);
DISPLAY 0.617021 (-1375 2750);
PAINT SKYBLUE (-1375 2750);
FORCEPROP 1 LAST PART_NUMBER G21796-009
J 0
(-1575 2850);
DISPLAY 0.617021 (-1575 2850);
PAINT BLUE (-1575 2850);
FORCEPROP 1 LAST VALUE 150.0
J 2
(-1475 2800);
DISPLAY 0.617021 (-1475 2800);
PAINT SKYBLUE (-1475 2800);
FORCEPROP 1 LAST LOCATION R7A17
J 0
(-1575 2900);
DISPLAY 0.617021 (-1575 2900);
PAINT AQUA (-1575 2900);
FORCEPROP 1 LAST PATH I21
J 0
(-1525 2875);
DISPLAY 0.978723 (-1525 2875);
PAINT WHITE (-1525 2875);
DISPLAY INVISIBLE (-1525 2875);
FORCEPROP 0 LAST CDS_SEC 1
J 0
(-1575 2950);
PAINT MONO (-1575 2950);
DISPLAY INVISIBLE (-1575 2950);
FORCEPROP 2 LAST CDS_LIB mstr_discrete
J 0
(-1475 2725);
PAINT ORANGE (-1475 2725);
DISPLAY INVISIBLE (-1475 2725);
FORCEPROP 2 LAST CDS_LOCATION R7A17
J 0
(-1575 2900);
DISPLAY 0.617021 (-1575 2900);
PAINT AQUA (-1575 2900);
DISPLAY INVISIBLE (-1575 2900);
FORCEPROP 2 LAST ROOM VDDQ_DEF_PWR_VR
J 0
(-1575 2950);
DISPLAY 1.361702 (-1575 2950);
PAINT ORANGE (-1575 2950);
DISPLAY INVISIBLE (-1575 2950);
FORCEPROP 2 LAST SEC 1
J 0
(-1525 2950);
DISPLAY 0.680851 (-1525 2950);
PAINT MONO (-1525 2950);
DISPLAY INVISIBLE (-1525 2950);
FORCEPROP 2 LAST SEC_TYPE 0402
J 0
(-1525 2950);
DISPLAY 1.021277 (-1525 2950);
PAINT ORANGE (-1525 2950);
DISPLAY INVISIBLE (-1525 2950);
FORCEADD PVCCIO_CPU0..1
(-1900 3675);
FORCEPROP 3 LASTPIN (-1900 3625) SIG_NAME PVCCIO_CPU0\g
J 0
(-1890 3635);
DISPLAY 0.659574 (-1890 3635);
PAINT MONO (-1890 3635);
DISPLAY INVISIBLE (-1890 3635);
FORCEPROP 1 LAST PATH I23
J 0
(-1850 3700);
DISPLAY 0.872340 (-1850 3700);
PAINT AQUA (-1850 3700);
DISPLAY INVISIBLE (-1850 3700);
FORCEPROP 1 LAST HDL_POWER PVCCIO_CPU0
J 1
(-1900 3725);
DISPLAY 0.872340 (-1900 3725);
PAINT GREEN (-1900 3725);
DISPLAY INVISIBLE (-1900 3725);
FORCEPROP 1 LAST BODY_TYPE PLUMBING
J 0
(-1945 3632);
DISPLAY 0.340426 (-1945 3632);
PAINT GREEN (-1945 3632);
DISPLAY INVISIBLE (-1945 3632);
FORCEPROP 2 LAST CDS_LIB mstr_symbols
J 0
(-1900 3675);
PAINT ORANGE (-1900 3675);
DISPLAY INVISIBLE (-1900 3675);
FORCEPROP 1 LAST VOLTAGE 1.1V
J 0
(-1945 3632);
DISPLAY 0.340426 (-1945 3632);
PAINT SKYBLUE (-1945 3632);
DISPLAY INVISIBLE (-1945 3632);
FORCEADD GND..1
(-1175 550);
FORCEPROP 3 LASTPIN (-1175 600) SIG_NAME GND\g
J 0
(-1165 610);
DISPLAY 0.659574 (-1165 610);
PAINT MONO (-1165 610);
DISPLAY INVISIBLE (-1165 610);
FORCEPROP 1 LAST PATH I24
J 0
(-1100 550);
DISPLAY 0.872340 (-1100 550);
PAINT AQUA (-1100 550);
DISPLAY INVISIBLE (-1100 550);
FORCEPROP 2 LAST ROOM VDDQ_DEF_PWR_VR
J 0
(-1750 625);
DISPLAY 1.361702 (-1750 625);
PAINT ORANGE (-1750 625);
DISPLAY INVISIBLE (-1750 625);
FORCEPROP 1 LAST BODY_TYPE PLUMBING
J 0
(-1220 507);
DISPLAY 0.340426 (-1220 507);
PAINT GREEN (-1220 507);
DISPLAY INVISIBLE (-1220 507);
FORCEPROP 1 LAST HDL_POWER GND
J 0
(-1175 700);
DISPLAY 1.170213 (-1175 700);
PAINT GREEN (-1175 700);
DISPLAY INVISIBLE (-1175 700);
FORCEPROP 2 LAST CDS_LIB mstr_symbols
J 0
(-1175 550);
PAINT ORANGE (-1175 550);
DISPLAY INVISIBLE (-1175 550);
FORCEPROP 1 LAST VOLTAGE 0
J 0
(-1175 550);
PAINT SKYBLUE (-1175 550);
DISPLAY INVISIBLE (-1175 550);
FORCEPROP 1 LAST SIZE 1B
J 0
(-1100 500);
DISPLAY 1.170213 (-1100 500);
PAINT AQUA (-1100 500);
DISPLAY INVISIBLE (-1100 500);
FORCEADD GND..1
(-1075 -400);
FORCEPROP 3 LASTPIN (-1075 -350) SIG_NAME GND\g
J 0
(-1065 -340);
DISPLAY 0.659574 (-1065 -340);
PAINT MONO (-1065 -340);
DISPLAY INVISIBLE (-1065 -340);
FORCEPROP 1 LAST HDL_POWER GND
J 0
(-1075 -250);
DISPLAY 1.170213 (-1075 -250);
PAINT GREEN (-1075 -250);
DISPLAY INVISIBLE (-1075 -250);
FORCEPROP 1 LAST VOLTAGE 0
J 0
(-1075 -400);
PAINT SKYBLUE (-1075 -400);
DISPLAY INVISIBLE (-1075 -400);
FORCEPROP 2 LAST CDS_LIB mstr_symbols
J 0
(-1075 -400);
PAINT ORANGE (-1075 -400);
DISPLAY INVISIBLE (-1075 -400);
FORCEPROP 1 LAST SIZE 1B
J 0
(-1000 -450);
DISPLAY 1.170213 (-1000 -450);
PAINT AQUA (-1000 -450);
DISPLAY INVISIBLE (-1000 -450);
FORCEPROP 1 LAST BODY_TYPE PLUMBING
J 0
(-1120 -443);
DISPLAY 0.340426 (-1120 -443);
PAINT GREEN (-1120 -443);
DISPLAY INVISIBLE (-1120 -443);
FORCEPROP 2 LAST ROOM VDDQ_DEF_PWR_VR
J 0
(-1650 -325);
DISPLAY 1.361702 (-1650 -325);
PAINT ORANGE (-1650 -325);
DISPLAY INVISIBLE (-1650 -325);
FORCEPROP 1 LAST PATH I25
J 0
(-1000 -400);
DISPLAY 0.872340 (-1000 -400);
PAINT AQUA (-1000 -400);
DISPLAY INVISIBLE (-1000 -400);
FORCEADD GND..1
(-775 -400);
FORCEPROP 3 LASTPIN (-775 -350) SIG_NAME GND\g
J 0
(-765 -340);
DISPLAY 0.659574 (-765 -340);
PAINT MONO (-765 -340);
DISPLAY INVISIBLE (-765 -340);
FORCEPROP 1 LAST HDL_POWER GND
J 0
(-775 -250);
DISPLAY 1.170213 (-775 -250);
PAINT GREEN (-775 -250);
DISPLAY INVISIBLE (-775 -250);
FORCEPROP 1 LAST VOLTAGE 0
J 0
(-775 -400);
PAINT SKYBLUE (-775 -400);
DISPLAY INVISIBLE (-775 -400);
FORCEPROP 1 LAST BODY_TYPE PLUMBING
J 0
(-820 -443);
DISPLAY 0.340426 (-820 -443);
PAINT GREEN (-820 -443);
DISPLAY INVISIBLE (-820 -443);
FORCEPROP 1 LAST SIZE 1B
J 0
(-700 -450);
DISPLAY 1.170213 (-700 -450);
PAINT AQUA (-700 -450);
DISPLAY INVISIBLE (-700 -450);
FORCEPROP 2 LAST CDS_LIB mstr_symbols
J 0
(-775 -400);
PAINT ORANGE (-775 -400);
DISPLAY INVISIBLE (-775 -400);
FORCEPROP 2 LAST ROOM VDDQ_DEF_PWR_VR
J 0
(-1350 -325);
DISPLAY 1.361702 (-1350 -325);
PAINT ORANGE (-1350 -325);
DISPLAY INVISIBLE (-1350 -325);
FORCEPROP 1 LAST PATH I26
J 0
(-700 -400);
DISPLAY 0.872340 (-700 -400);
PAINT AQUA (-700 -400);
DISPLAY INVISIBLE (-700 -400);
FORCEADD GND..1
(1950 -300);
FORCEPROP 3 LASTPIN (1950 -250) SIG_NAME GND\g
J 0
(1960 -240);
DISPLAY 0.659574 (1960 -240);
PAINT MONO (1960 -240);
DISPLAY INVISIBLE (1960 -240);
FORCEPROP 1 LAST PATH I27
J 0
(2025 -300);
DISPLAY 0.872340 (2025 -300);
PAINT AQUA (2025 -300);
DISPLAY INVISIBLE (2025 -300);
FORCEPROP 2 LAST ROOM VDDQ_DEF_PWR_VR
J 0
(1375 -225);
DISPLAY 1.361702 (1375 -225);
PAINT ORANGE (1375 -225);
DISPLAY INVISIBLE (1375 -225);
FORCEPROP 1 LAST VOLTAGE 0
J 0
(1950 -300);
PAINT SKYBLUE (1950 -300);
DISPLAY INVISIBLE (1950 -300);
FORCEPROP 2 LAST CDS_LIB mstr_symbols
J 0
(1950 -300);
PAINT ORANGE (1950 -300);
DISPLAY INVISIBLE (1950 -300);
FORCEPROP 1 LAST BODY_TYPE PLUMBING
J 0
(1905 -343);
DISPLAY 0.340426 (1905 -343);
PAINT GREEN (1905 -343);
DISPLAY INVISIBLE (1905 -343);
FORCEPROP 1 LAST HDL_POWER GND
J 0
(1950 -150);
DISPLAY 1.170213 (1950 -150);
PAINT GREEN (1950 -150);
DISPLAY INVISIBLE (1950 -150);
FORCEPROP 1 LAST SIZE 1B
J 0
(2025 -350);
DISPLAY 1.170213 (2025 -350);
PAINT AQUA (2025 -350);
DISPLAY INVISIBLE (2025 -350);
FORCEADD CAP_A..1
(1950 -100);
FORCEPROP 1 LAST PACK_TYPE 0402V
J 0
(2000 -300);
DISPLAY 0.617021 (2000 -300);
PAINT SKYBLUE (2000 -300);
FORCEPROP 1 LAST PART_NUMBER A36096-030
J 0
(2000 -250);
DISPLAY 0.617021 (2000 -250);
PAINT BLUE (2000 -250);
FORCEPROP 1 LAST MATERIAL X7R
J 0
(2000 -200);
DISPLAY 0.617021 (2000 -200);
PAINT SKYBLUE (2000 -200);
FORCEPROP 1 LAST TOLERANCE 10%
J 0
(2000 -150);
DISPLAY 0.617021 (2000 -150);
PAINT SKYBLUE (2000 -150);
FORCEPROP 1 LAST VOLTAGE 16V
J 0
(2000 -100);
DISPLAY 0.617021 (2000 -100);
PAINT SKYBLUE (2000 -100);
FORCEPROP 1 LAST VALUE 0.1UF
J 0
(2000 -50);
DISPLAY 0.617021 (2000 -50);
PAINT SKYBLUE (2000 -50);
FORCEPROP 1 LASTPIN (1950 -200) $PN 2
J 0
(1960 -220);
DISPLAY 0.617021 (1960 -220);
PAINT ORANGE (1960 -220);
FORCEPROP 1 LAST LOCATION C7B2
J 0
(2000 0);
DISPLAY 0.617021 (2000 0);
PAINT AQUA (2000 0);
FORCEPROP 1 LASTPIN (1950 0) $PN 1
J 0
(1960 -20);
DISPLAY 0.617021 (1960 -20);
PAINT ORANGE (1960 -20);
FORCEPROP 1 LAST PATH I28
J 0
(2000 50);
DISPLAY 0.978723 (2000 50);
PAINT WHITE (2000 50);
DISPLAY INVISIBLE (2000 50);
FORCEPROP 2 LAST CDS_LIB dev_discrete
J 0
(1950 -100);
PAINT ORANGE (1950 -100);
DISPLAY INVISIBLE (1950 -100);
FORCEPROP 2 LAST SEC 1
J 0
(2000 125);
DISPLAY 0.680851 (2000 125);
PAINT MONO (2000 125);
DISPLAY INVISIBLE (2000 125);
FORCEPROP 2 LAST CDS_SEC 1
J 0
(2000 50);
PAINT ORANGE (2000 50);
DISPLAY INVISIBLE (2000 50);
FORCEPROP 2 LAST CDS_LOCATION C7B2
J 0
(2000 0);
DISPLAY 0.617021 (2000 0);
PAINT AQUA (2000 0);
DISPLAY INVISIBLE (2000 0);
FORCEPROP 2 LAST ROOM VDDQ_DEF_PWR_VR
J 0
(2000 50);
DISPLAY 1.361702 (2000 50);
PAINT ORANGE (2000 50);
DISPLAY INVISIBLE (2000 50);
FORCEPROP 2 LAST SEC_TYPE 0402V
J 0
(2000 125);
DISPLAY 1.021277 (2000 125);
PAINT ORANGE (2000 125);
DISPLAY INVISIBLE (2000 125);
FORCEADD GND..1
(2350 -375);
FORCEPROP 3 LASTPIN (2350 -325) SIG_NAME GND\g
J 0
(2360 -315);
DISPLAY 0.659574 (2360 -315);
PAINT MONO (2360 -315);
DISPLAY INVISIBLE (2360 -315);
FORCEPROP 1 LAST PATH I29
J 0
(2425 -375);
DISPLAY 0.872340 (2425 -375);
PAINT AQUA (2425 -375);
DISPLAY INVISIBLE (2425 -375);
FORCEPROP 2 LAST ROOM VDDQ_DEF_PWR_VR
J 0
(1775 -300);
DISPLAY 1.361702 (1775 -300);
PAINT ORANGE (1775 -300);
DISPLAY INVISIBLE (1775 -300);
FORCEPROP 1 LAST BODY_TYPE PLUMBING
J 0
(2305 -418);
DISPLAY 0.340426 (2305 -418);
PAINT GREEN (2305 -418);
DISPLAY INVISIBLE (2305 -418);
FORCEPROP 1 LAST VOLTAGE 0
J 0
(2350 -375);
PAINT SKYBLUE (2350 -375);
DISPLAY INVISIBLE (2350 -375);
FORCEPROP 2 LAST CDS_LIB mstr_symbols
J 0
(2350 -375);
PAINT ORANGE (2350 -375);
DISPLAY INVISIBLE (2350 -375);
FORCEPROP 1 LAST HDL_POWER GND
J 0
(2350 -225);
DISPLAY 1.170213 (2350 -225);
PAINT GREEN (2350 -225);
DISPLAY INVISIBLE (2350 -225);
FORCEPROP 1 LAST SIZE 1B
J 0
(2425 -425);
DISPLAY 1.170213 (2425 -425);
PAINT AQUA (2425 -425);
DISPLAY INVISIBLE (2425 -425);
FORCEADD OFFPAGE..1
(-3550 875);
FORCEPROP 2 LAST $XR0 220 
J 0
(-3802 875);
DISPLAY 0.638298 (-3802 875);
PAINT MONO (-3802 875);
FORCEPROP 2 LAST PATH I3
J 0
(-3800 925);
DISPLAY 1.021277 (-3800 925);
PAINT ORANGE (-3800 925);
DISPLAY INVISIBLE (-3800 925);
FORCEPROP 2 LAST CDS_LIB mstr_standard
J 0
(-3550 875);
PAINT ORANGE (-3550 875);
DISPLAY INVISIBLE (-3550 875);
FORCEPROP 1 LAST COMMENT_BODY TRUE
J 0
(-3425 775);
DISPLAY 1.170213 (-3425 775);
PAINT GREEN (-3425 775);
DISPLAY INVISIBLE (-3425 775);
FORCEPROP 1 LAST OFFPAGE TRUE
J 0
(-3225 750);
DISPLAY 1.170213 (-3225 750);
PAINT GREEN (-3225 750);
DISPLAY INVISIBLE (-3225 750);
FORCEPROP 2 LAST ROOM VDDQ_DEF_PWR_VR
J 0
(-4100 950);
DISPLAY 1.361702 (-4100 950);
PAINT ORANGE (-4100 950);
DISPLAY INVISIBLE (-4100 950);
FORCEADD CAP_A..1
(2350 -100);
FORCEPROP 1 LAST PACK_TYPE 0402V
J 0
(2400 -300);
DISPLAY 0.617021 (2400 -300);
PAINT SKYBLUE (2400 -300);
FORCEPROP 1 LAST PART_NUMBER D97712-004
J 0
(2400 -250);
DISPLAY 0.617021 (2400 -250);
PAINT BLUE (2400 -250);
FORCEPROP 1 LAST MATERIAL X6S
J 0
(2400 -200);
DISPLAY 0.617021 (2400 -200);
PAINT SKYBLUE (2400 -200);
FORCEPROP 1 LAST TOLERANCE 10%
J 0
(2400 -150);
DISPLAY 0.617021 (2400 -150);
PAINT SKYBLUE (2400 -150);
FORCEPROP 1 LAST VOLTAGE 6.3V
J 0
(2400 -100);
DISPLAY 0.617021 (2400 -100);
PAINT SKYBLUE (2400 -100);
FORCEPROP 1 LAST VALUE 1.0UF
J 0
(2400 -50);
DISPLAY 0.617021 (2400 -50);
PAINT SKYBLUE (2400 -50);
FORCEPROP 1 LASTPIN (2350 -200) $PN 2
J 0
(2360 -220);
DISPLAY 0.617021 (2360 -220);
PAINT ORANGE (2360 -220);
FORCEPROP 1 LASTPIN (2350 0) $PN 1
J 0
(2360 -20);
DISPLAY 0.617021 (2360 -20);
PAINT ORANGE (2360 -20);
FORCEPROP 1 LAST LOCATION C7B1
J 0
(2400 0);
DISPLAY 0.617021 (2400 0);
PAINT AQUA (2400 0);
FORCEPROP 1 LAST PATH I30
J 0
(2400 50);
DISPLAY 0.978723 (2400 50);
PAINT WHITE (2400 50);
DISPLAY INVISIBLE (2400 50);
FORCEPROP 2 LAST CDS_LIB dev_discrete
J 0
(2350 -100);
PAINT ORANGE (2350 -100);
DISPLAY INVISIBLE (2350 -100);
FORCEPROP 2 LAST CDS_LOCATION C7B1
J 0
(2400 0);
DISPLAY 0.617021 (2400 0);
PAINT AQUA (2400 0);
DISPLAY INVISIBLE (2400 0);
FORCEPROP 2 LAST CDS_SEC 1
J 0
(2400 50);
PAINT ORANGE (2400 50);
DISPLAY INVISIBLE (2400 50);
FORCEPROP 2 LAST SEC_TYPE 0402V
J 0
(2400 100);
DISPLAY 1.021277 (2400 100);
PAINT ORANGE (2400 100);
DISPLAY INVISIBLE (2400 100);
FORCEPROP 2 LAST SEC 1
J 0
(2400 100);
DISPLAY 0.680851 (2400 100);
PAINT MONO (2400 100);
DISPLAY INVISIBLE (2400 100);
FORCEPROP 2 LAST ROOM VDDQ_DEF_PWR_VR
J 0
(2400 50);
DISPLAY 1.361702 (2400 50);
PAINT ORANGE (2400 50);
DISPLAY INVISIBLE (2400 50);
FORCEADD GND..1
(725 525);
FORCEPROP 3 LASTPIN (725 575) SIG_NAME GND\g
J 0
(735 585);
DISPLAY 0.659574 (735 585);
PAINT MONO (735 585);
DISPLAY INVISIBLE (735 585);
FORCEPROP 1 LAST PATH I33
J 0
(800 525);
DISPLAY 0.872340 (800 525);
PAINT AQUA (800 525);
DISPLAY INVISIBLE (800 525);
FORCEPROP 2 LAST ROOM VDDQ_DEF_PWR_VR
J 0
(150 600);
DISPLAY 1.361702 (150 600);
PAINT ORANGE (150 600);
DISPLAY INVISIBLE (150 600);
FORCEPROP 1 LAST VOLTAGE 0
J 0
(725 525);
PAINT SKYBLUE (725 525);
DISPLAY INVISIBLE (725 525);
FORCEPROP 2 LAST CDS_LIB mstr_symbols
J 0
(725 525);
PAINT ORANGE (725 525);
DISPLAY INVISIBLE (725 525);
FORCEPROP 1 LAST SIZE 1B
J 0
(800 475);
DISPLAY 1.170213 (800 475);
PAINT AQUA (800 475);
DISPLAY INVISIBLE (800 475);
FORCEPROP 1 LAST BODY_TYPE PLUMBING
J 0
(680 482);
DISPLAY 0.340426 (680 482);
PAINT GREEN (680 482);
DISPLAY INVISIBLE (680 482);
FORCEPROP 1 LAST HDL_POWER GND
J 0
(725 675);
DISPLAY 1.170213 (725 675);
PAINT GREEN (725 675);
DISPLAY INVISIBLE (725 675);
FORCEADD RES..2
(-1150 3225);
FORCEPROP 1 LASTPIN (-1150 3325) $PN 1
J 0
(-1145 3287);
DISPLAY 0.787234 (-1145 3287);
PAINT ORANGE (-1145 3287);
FORCEPROP 1 LAST PACK_TYPE 0402
J 0
(-1110 3050);
DISPLAY 0.617021 (-1110 3050);
PAINT SKYBLUE (-1110 3050);
FORCEPROP 1 LAST PART_NUMBER G21796-010
J 0
(-1110 3100);
DISPLAY 0.617021 (-1110 3100);
PAINT BLUE (-1110 3100);
FORCEPROP 1 LAST MATERIAL EMPTY
J 0
(-1110 3150);
DISPLAY 0.617021 (-1110 3150);
PAINT RED (-1110 3150);
FORCEPROP 1 LAST WATTAGE 1/16W
J 0
(-1110 3200);
DISPLAY 0.617021 (-1110 3200);
PAINT SKYBLUE (-1110 3200);
FORCEPROP 1 LAST TOLERANCE 1%
J 0
(-1105 3250);
DISPLAY 0.617021 (-1105 3250);
PAINT SKYBLUE (-1105 3250);
FORCEPROP 1 LAST VALUE 100.0K
J 0
(-1105 3300);
DISPLAY 0.617021 (-1105 3300);
PAINT SKYBLUE (-1105 3300);
FORCEPROP 1 LAST LOCATION R3M5
J 0
(-1105 3350);
DISPLAY 0.617021 (-1105 3350);
PAINT AQUA (-1105 3350);
FORCEPROP 1 LASTPIN (-1150 3125) $PN 2
J 0
(-1145 3135);
DISPLAY 0.787234 (-1145 3135);
PAINT ORANGE (-1145 3135);
FORCEPROP 1 LAST PATH I34
J 0
(-1100 3400);
DISPLAY 0.978723 (-1100 3400);
PAINT WHITE (-1100 3400);
DISPLAY INVISIBLE (-1100 3400);
FORCEPROP 0 LAST CDS_SEC 1
J 0
(-1100 3400);
PAINT MONO (-1100 3400);
DISPLAY INVISIBLE (-1100 3400);
FORCEPROP 2 LAST CDS_LIB mstr_discrete
J 0
(-1150 3225);
PAINT ORANGE (-1150 3225);
DISPLAY INVISIBLE (-1150 3225);
FORCEPROP 2 LAST CDS_LOCATION R3M5
J 0
(-1105 3350);
DISPLAY 0.617021 (-1105 3350);
PAINT AQUA (-1105 3350);
DISPLAY INVISIBLE (-1105 3350);
FORCEPROP 0 LAST ROOM VDDQ_DEF_PWR_VR
J 0
(-1100 3450);
DISPLAY 0.617021 (-1100 3450);
PAINT ORANGE (-1100 3450);
DISPLAY INVISIBLE (-1100 3450);
FORCEPROP 0 LAST BOM_COST SM_CONTROLLER
J 0
(-1100 3550);
DISPLAY 1.021277 (-1100 3550);
PAINT ORANGE (-1100 3550);
DISPLAY INVISIBLE (-1100 3550);
FORCEPROP 2 LAST SEC 1
J 0
(-1100 3450);
PAINT MONO (-1100 3450);
DISPLAY INVISIBLE (-1100 3450);
FORCEPROP 2 LAST SEC_TYPE 0402
J 0
(-1100 3450);
DISPLAY 1.021277 (-1100 3450);
PAINT ORANGE (-1100 3450);
DISPLAY INVISIBLE (-1100 3450);
FORCEADD RES..2
(-450 3150);
FORCEPROP 1 LAST PACK_TYPE 0402
J 0
(-410 2975);
DISPLAY 0.617021 (-410 2975);
PAINT SKYBLUE (-410 2975);
FORCEPROP 1 LAST PART_NUMBER G21497-005
J 0
(-410 3025);
DISPLAY 0.617021 (-410 3025);
PAINT BLUE (-410 3025);
FORCEPROP 1 LAST MATERIAL CHIP
J 0
(-410 3075);
DISPLAY 0.617021 (-410 3075);
PAINT SKYBLUE (-410 3075);
FORCEPROP 1 LAST WATTAGE 1/16W
J 0
(-410 3125);
DISPLAY 0.617021 (-410 3125);
PAINT SKYBLUE (-410 3125);
FORCEPROP 1 LAST TOLERANCE 5%
J 0
(-405 3175);
DISPLAY 0.617021 (-405 3175);
PAINT SKYBLUE (-405 3175);
FORCEPROP 1 LAST VALUE 0.0
J 0
(-405 3225);
DISPLAY 0.617021 (-405 3225);
PAINT SKYBLUE (-405 3225);
FORCEPROP 1 LAST LOCATION R3M1
J 0
(-405 3275);
DISPLAY 0.617021 (-405 3275);
PAINT AQUA (-405 3275);
FORCEPROP 1 LASTPIN (-450 3050) $PN 2
J 0
(-445 3060);
DISPLAY 0.617021 (-445 3060);
PAINT ORANGE (-445 3060);
FORCEPROP 1 LASTPIN (-450 3250) $PN 1
J 0
(-445 3212);
DISPLAY 0.617021 (-445 3212);
PAINT ORANGE (-445 3212);
FORCEPROP 1 LAST PATH I35
J 0
(-400 3325);
DISPLAY 0.978723 (-400 3325);
PAINT WHITE (-400 3325);
DISPLAY INVISIBLE (-400 3325);
FORCEPROP 0 LAST CDS_SEC 1
J 0
(-400 3325);
PAINT MONO (-400 3325);
DISPLAY INVISIBLE (-400 3325);
FORCEPROP 2 LAST CDS_LIB mstr_discrete
J 0
(-450 3150);
PAINT ORANGE (-450 3150);
DISPLAY INVISIBLE (-450 3150);
FORCEPROP 2 LAST SEC_TYPE 0402
J 0
(-400 3400);
DISPLAY 1.021277 (-400 3400);
PAINT ORANGE (-400 3400);
DISPLAY INVISIBLE (-400 3400);
FORCEPROP 2 LAST SEC 1
J 0
(-400 3400);
DISPLAY 0.680851 (-400 3400);
PAINT MONO (-400 3400);
DISPLAY INVISIBLE (-400 3400);
FORCEPROP 2 LAST CDS_LOCATION R3M1
J 0
(-405 3275);
DISPLAY 0.617021 (-405 3275);
PAINT AQUA (-405 3275);
DISPLAY INVISIBLE (-405 3275);
FORCEPROP 2 LAST ROOM VDDQ_DEF_PWR_VR
J 0
(-400 3325);
DISPLAY 1.361702 (-400 3325);
PAINT ORANGE (-400 3325);
DISPLAY INVISIBLE (-400 3325);
FORCEADD P3V3_STBY..1
(-450 3650);
FORCEPROP 3 LASTPIN (-450 3600) SIG_NAME P3V3_STBY\g
J 0
(-440 3610);
DISPLAY 0.659574 (-440 3610);
PAINT MONO (-440 3610);
DISPLAY INVISIBLE (-440 3610);
FORCEPROP 1 LAST PATH I36
J 0
(-405 3652);
DISPLAY 0.340426 (-405 3652);
PAINT GREEN (-405 3652);
DISPLAY INVISIBLE (-405 3652);
FORCEPROP 1 LAST HDL_POWER P3V3_STBY
J 0
(-750 3525);
DISPLAY 0.872340 (-750 3525);
PAINT ORANGE (-750 3525);
DISPLAY INVISIBLE (-750 3525);
FORCEPROP 1 LAST BODY_TYPE PLUMBING
J 0
(-495 3607);
DISPLAY 0.340426 (-495 3607);
PAINT GREEN (-495 3607);
DISPLAY INVISIBLE (-495 3607);
FORCEPROP 1 LAST VOLTAGE 3.3V
J 0
(-495 3607);
DISPLAY 0.340426 (-495 3607);
PAINT SKYBLUE (-495 3607);
DISPLAY INVISIBLE (-495 3607);
FORCEPROP 2 LAST CDS_LIB mstr_symbols
J 0
(-450 3650);
PAINT ORANGE (-450 3650);
DISPLAY INVISIBLE (-450 3650);
FORCEPROP 1 LAST SIZE 1B
J 0
(-405 3672);
DISPLAY 0.340426 (-405 3672);
PAINT GREEN (-405 3672);
DISPLAY INVISIBLE (-405 3672);
FORCEADD GND..1
(-150 2600);
FORCEPROP 3 LASTPIN (-150 2650) SIG_NAME GND\g
J 0
(-140 2660);
DISPLAY 0.659574 (-140 2660);
PAINT MONO (-140 2660);
DISPLAY INVISIBLE (-140 2660);
FORCEPROP 1 LAST PATH I37
J 0
(-75 2600);
DISPLAY 0.872340 (-75 2600);
PAINT AQUA (-75 2600);
DISPLAY INVISIBLE (-75 2600);
FORCEPROP 2 LAST ROOM VDDQ_DEF_PWR_VR
J 0
(-725 2675);
DISPLAY 1.361702 (-725 2675);
PAINT ORANGE (-725 2675);
DISPLAY INVISIBLE (-725 2675);
FORCEPROP 1 LAST BODY_TYPE PLUMBING
J 0
(-195 2557);
DISPLAY 0.340426 (-195 2557);
PAINT GREEN (-195 2557);
DISPLAY INVISIBLE (-195 2557);
FORCEPROP 1 LAST VOLTAGE 0
J 0
(-150 2600);
PAINT SKYBLUE (-150 2600);
DISPLAY INVISIBLE (-150 2600);
FORCEPROP 1 LAST SIZE 1B
J 0
(-75 2550);
DISPLAY 1.170213 (-75 2550);
PAINT AQUA (-75 2550);
DISPLAY INVISIBLE (-75 2550);
FORCEPROP 2 LAST CDS_LIB mstr_symbols
J 0
(-150 2600);
PAINT ORANGE (-150 2600);
DISPLAY INVISIBLE (-150 2600);
FORCEPROP 1 LAST HDL_POWER GND
J 0
(-150 2750);
DISPLAY 1.170213 (-150 2750);
PAINT GREEN (-150 2750);
DISPLAY INVISIBLE (-150 2750);
FORCEADD CAP_A..1
(-150 2800);
FORCEPROP 1 LAST MATERIAL X7R
J 0
(-100 2700);
DISPLAY 0.617021 (-100 2700);
PAINT SKYBLUE (-100 2700);
FORCEPROP 1 LAST PACK_TYPE 0402V
J 0
(-100 2600);
DISPLAY 0.617021 (-100 2600);
PAINT SKYBLUE (-100 2600);
FORCEPROP 1 LAST PART_NUMBER A36096-030
J 0
(-100 2650);
DISPLAY 0.617021 (-100 2650);
PAINT BLUE (-100 2650);
FORCEPROP 1 LAST TOLERANCE 10%
J 0
(-100 2750);
DISPLAY 0.617021 (-100 2750);
PAINT SKYBLUE (-100 2750);
FORCEPROP 1 LAST VOLTAGE 16V
J 0
(-100 2800);
DISPLAY 0.617021 (-100 2800);
PAINT SKYBLUE (-100 2800);
FORCEPROP 1 LAST VALUE 0.1UF
J 0
(-100 2850);
DISPLAY 0.617021 (-100 2850);
PAINT SKYBLUE (-100 2850);
FORCEPROP 1 LASTPIN (-150 2700) $PN 2
J 0
(-140 2680);
DISPLAY 0.617021 (-140 2680);
PAINT ORANGE (-140 2680);
FORCEPROP 1 LASTPIN (-150 2900) $PN 1
J 0
(-140 2880);
DISPLAY 0.617021 (-140 2880);
PAINT ORANGE (-140 2880);
FORCEPROP 1 LAST LOCATION C7A38
J 0
(-100 2900);
DISPLAY 0.617021 (-100 2900);
PAINT AQUA (-100 2900);
FORCEPROP 1 LAST PATH I38
J 0
(-100 2950);
DISPLAY 0.978723 (-100 2950);
PAINT WHITE (-100 2950);
DISPLAY INVISIBLE (-100 2950);
FORCEPROP 2 LAST CDS_LOCATION C7A38
J 0
(-100 2900);
DISPLAY 0.617021 (-100 2900);
PAINT AQUA (-100 2900);
DISPLAY INVISIBLE (-100 2900);
FORCEPROP 2 LAST CDS_LIB dev_discrete
J 0
(-150 2800);
PAINT ORANGE (-150 2800);
DISPLAY INVISIBLE (-150 2800);
FORCEPROP 2 LAST CDS_SEC 1
J 0
(-100 2950);
PAINT ORANGE (-100 2950);
DISPLAY INVISIBLE (-100 2950);
FORCEPROP 2 LAST ROOM VDDQ_DEF_PWR_VR
J 0
(-100 2950);
DISPLAY 1.361702 (-100 2950);
PAINT ORANGE (-100 2950);
DISPLAY INVISIBLE (-100 2950);
FORCEPROP 2 LAST SEC_TYPE 0402V
J 0
(-100 3025);
DISPLAY 1.021277 (-100 3025);
PAINT ORANGE (-100 3025);
DISPLAY INVISIBLE (-100 3025);
FORCEPROP 2 LAST SEC 1
J 0
(-100 3025);
DISPLAY 0.680851 (-100 3025);
PAINT MONO (-100 3025);
DISPLAY INVISIBLE (-100 3025);
FORCEADD GND..1
(250 2600);
FORCEPROP 3 LASTPIN (250 2650) SIG_NAME GND\g
J 0
(260 2660);
DISPLAY 0.659574 (260 2660);
PAINT MONO (260 2660);
DISPLAY INVISIBLE (260 2660);
FORCEPROP 1 LAST PATH I39
J 0
(325 2600);
DISPLAY 0.872340 (325 2600);
PAINT AQUA (325 2600);
DISPLAY INVISIBLE (325 2600);
FORCEPROP 2 LAST ROOM VDDQ_DEF_PWR_VR
J 0
(-325 2675);
DISPLAY 1.361702 (-325 2675);
PAINT ORANGE (-325 2675);
DISPLAY INVISIBLE (-325 2675);
FORCEPROP 1 LAST BODY_TYPE PLUMBING
J 0
(205 2557);
DISPLAY 0.340426 (205 2557);
PAINT GREEN (205 2557);
DISPLAY INVISIBLE (205 2557);
FORCEPROP 1 LAST VOLTAGE 0
J 0
(250 2600);
PAINT SKYBLUE (250 2600);
DISPLAY INVISIBLE (250 2600);
FORCEPROP 2 LAST CDS_LIB mstr_symbols
J 0
(250 2600);
PAINT ORANGE (250 2600);
DISPLAY INVISIBLE (250 2600);
FORCEPROP 1 LAST SIZE 1B
J 0
(325 2550);
DISPLAY 1.170213 (325 2550);
PAINT AQUA (325 2550);
DISPLAY INVISIBLE (325 2550);
FORCEPROP 1 LAST HDL_POWER GND
J 0
(250 2750);
DISPLAY 1.170213 (250 2750);
PAINT GREEN (250 2750);
DISPLAY INVISIBLE (250 2750);
FORCEADD OFFPAGE..1
(-3525 1200);
FORCEPROP 2 LAST $XR0 191 
J 0
(-3777 1200);
DISPLAY 0.638298 (-3777 1200);
PAINT MONO (-3777 1200);
FORCEPROP 2 LAST PATH I4
J 0
(-3775 1250);
DISPLAY 1.021277 (-3775 1250);
PAINT ORANGE (-3775 1250);
DISPLAY INVISIBLE (-3775 1250);
FORCEPROP 2 LAST ROOM VDDQ_DEF_PWR_VR
J 0
(-4075 1275);
DISPLAY 1.361702 (-4075 1275);
PAINT ORANGE (-4075 1275);
DISPLAY INVISIBLE (-4075 1275);
FORCEPROP 2 LAST CDS_LIB mstr_standard
J 0
(-3525 1200);
PAINT ORANGE (-3525 1200);
DISPLAY INVISIBLE (-3525 1200);
FORCEPROP 1 LAST COMMENT_BODY TRUE
J 0
(-3400 1100);
DISPLAY 1.170213 (-3400 1100);
PAINT GREEN (-3400 1100);
DISPLAY INVISIBLE (-3400 1100);
FORCEPROP 1 LAST OFFPAGE TRUE
J 0
(-3200 1075);
DISPLAY 1.170213 (-3200 1075);
PAINT GREEN (-3200 1075);
DISPLAY INVISIBLE (-3200 1075);
FORCEADD CAP_A..1
(250 2800);
FORCEPROP 1 LAST PART_NUMBER D97712-004
J 0
(300 2650);
DISPLAY 0.617021 (300 2650);
PAINT BLUE (300 2650);
FORCEPROP 1 LAST PACK_TYPE 0402V
J 0
(300 2600);
DISPLAY 0.617021 (300 2600);
PAINT SKYBLUE (300 2600);
FORCEPROP 1 LAST MATERIAL X6S
J 0
(300 2700);
DISPLAY 0.617021 (300 2700);
PAINT SKYBLUE (300 2700);
FORCEPROP 1 LAST TOLERANCE 10%
J 0
(300 2750);
DISPLAY 0.617021 (300 2750);
PAINT SKYBLUE (300 2750);
FORCEPROP 1 LAST VOLTAGE 6.3V
J 0
(300 2800);
DISPLAY 0.617021 (300 2800);
PAINT SKYBLUE (300 2800);
FORCEPROP 1 LAST VALUE 1.0UF
J 0
(300 2850);
DISPLAY 0.617021 (300 2850);
PAINT SKYBLUE (300 2850);
FORCEPROP 1 LASTPIN (250 2700) $PN 2
J 0
(260 2680);
DISPLAY 0.617021 (260 2680);
PAINT ORANGE (260 2680);
FORCEPROP 1 LASTPIN (250 2900) $PN 1
J 0
(260 2880);
DISPLAY 0.617021 (260 2880);
PAINT ORANGE (260 2880);
FORCEPROP 1 LAST LOCATION C7A37
J 0
(300 2900);
DISPLAY 0.617021 (300 2900);
PAINT AQUA (300 2900);
FORCEPROP 1 LAST PATH I40
J 0
(300 2950);
DISPLAY 0.978723 (300 2950);
PAINT WHITE (300 2950);
DISPLAY INVISIBLE (300 2950);
FORCEPROP 2 LAST CDS_LIB dev_discrete
J 0
(250 2800);
PAINT ORANGE (250 2800);
DISPLAY INVISIBLE (250 2800);
FORCEPROP 2 LAST CDS_LOCATION C7A37
J 0
(300 2900);
DISPLAY 0.617021 (300 2900);
PAINT AQUA (300 2900);
DISPLAY INVISIBLE (300 2900);
FORCEPROP 2 LAST ROOM VDDQ_DEF_PWR_VR
J 0
(300 2950);
DISPLAY 1.361702 (300 2950);
PAINT ORANGE (300 2950);
DISPLAY INVISIBLE (300 2950);
FORCEPROP 2 LAST CDS_SEC 1
J 0
(300 2950);
PAINT ORANGE (300 2950);
DISPLAY INVISIBLE (300 2950);
FORCEPROP 2 LAST SEC_TYPE 0402V
J 0
(300 3000);
DISPLAY 1.021277 (300 3000);
PAINT ORANGE (300 3000);
DISPLAY INVISIBLE (300 3000);
FORCEPROP 2 LAST SEC 1
J 0
(300 3000);
DISPLAY 0.680851 (300 3000);
PAINT MONO (300 3000);
DISPLAY INVISIBLE (300 3000);
FORCEADD CAP..1
(1625 925);
FORCEPROP 1 LAST PACK_TYPE 0402LF
J 0
(1675 725);
DISPLAY 0.617021 (1675 725);
PAINT SKYBLUE (1675 725);
FORCEPROP 1 LASTPIN (1625 825) $PN 2
J 0
(1635 805);
DISPLAY 0.617021 (1635 805);
PAINT ORANGE (1635 805);
FORCEPROP 1 LAST MATERIAL X7R
J 0
(1675 825);
DISPLAY 0.617021 (1675 825);
PAINT SKYBLUE (1675 825);
FORCEPROP 1 LAST PART_NUMBER A36096-046
J 0
(1675 775);
DISPLAY 0.617021 (1675 775);
PAINT BLUE (1675 775);
FORCEPROP 1 LAST LOCATION C7B3
J 0
(1675 1025);
DISPLAY 0.617021 (1675 1025);
PAINT AQUA (1675 1025);
FORCEPROP 1 LAST TOLERANCE 10%
J 0
(1675 875);
DISPLAY 0.617021 (1675 875);
PAINT SKYBLUE (1675 875);
FORCEPROP 1 LAST VOLTAGE 50V
J 0
(1675 925);
DISPLAY 0.617021 (1675 925);
PAINT SKYBLUE (1675 925);
FORCEPROP 1 LAST VALUE 1000PF
J 0
(1675 975);
DISPLAY 0.617021 (1675 975);
PAINT SKYBLUE (1675 975);
FORCEPROP 1 LASTPIN (1625 1025) $PN 1
J 0
(1635 1005);
DISPLAY 0.617021 (1635 1005);
PAINT ORANGE (1635 1005);
FORCEPROP 1 LAST PATH I41
J 0
(1675 1075);
DISPLAY 0.978723 (1675 1075);
PAINT WHITE (1675 1075);
DISPLAY INVISIBLE (1675 1075);
FORCEPROP 0 LAST CDS_SEC 1
J 0
(1675 1075);
PAINT MONO (1675 1075);
DISPLAY INVISIBLE (1675 1075);
FORCEPROP 2 LAST CDS_LIB mstr_discrete
J 0
(1625 925);
PAINT MONO (1625 925);
DISPLAY INVISIBLE (1625 925);
FORCEPROP 0 LAST ROOM VDDQ_DEF_PWR_VR
J 0
(1675 1125);
DISPLAY 1.021277 (1675 1125);
PAINT ORANGE (1675 1125);
DISPLAY INVISIBLE (1675 1125);
FORCEPROP 2 LAST CDS_LOCATION C7B3
J 0
(1675 1025);
DISPLAY 0.617021 (1675 1025);
PAINT AQUA (1675 1025);
DISPLAY INVISIBLE (1675 1025);
FORCEPROP 2 LAST SEC 1
J 0
(1675 1125);
DISPLAY 0.680851 (1675 1125);
PAINT MONO (1675 1125);
DISPLAY INVISIBLE (1675 1125);
FORCEPROP 2 LAST SEC_TYPE 0402LF
J 0
(1675 1125);
DISPLAY 1.021277 (1675 1125);
PAINT ORANGE (1675 1125);
DISPLAY INVISIBLE (1675 1125);
FORCEADD GND..1
(1625 700);
FORCEPROP 3 LASTPIN (1625 750) SIG_NAME GND\g
J 0
(1635 760);
DISPLAY 0.659574 (1635 760);
PAINT MONO (1635 760);
DISPLAY INVISIBLE (1635 760);
FORCEPROP 1 LAST PATH I42
J 0
(1700 700);
DISPLAY 0.872340 (1700 700);
PAINT AQUA (1700 700);
DISPLAY INVISIBLE (1700 700);
FORCEPROP 2 LAST ROOM VDDQ_DEF_PWR_VR
J 0
(1050 775);
DISPLAY 1.361702 (1050 775);
PAINT ORANGE (1050 775);
DISPLAY INVISIBLE (1050 775);
FORCEPROP 1 LAST HDL_POWER GND
J 0
(1625 850);
DISPLAY 1.170213 (1625 850);
PAINT GREEN (1625 850);
DISPLAY INVISIBLE (1625 850);
FORCEPROP 1 LAST VOLTAGE 0
J 0
(1625 700);
PAINT SKYBLUE (1625 700);
DISPLAY INVISIBLE (1625 700);
FORCEPROP 2 LAST CDS_LIB mstr_symbols
J 0
(1625 700);
PAINT MONO (1625 700);
DISPLAY INVISIBLE (1625 700);
FORCEPROP 1 LAST BODY_TYPE PLUMBING
J 0
(1580 657);
DISPLAY 0.340426 (1580 657);
PAINT GREEN (1580 657);
DISPLAY INVISIBLE (1580 657);
FORCEPROP 1 LAST SIZE 1B
J 0
(1700 650);
DISPLAY 1.170213 (1700 650);
PAINT AQUA (1700 650);
DISPLAY INVISIBLE (1700 650);
FORCEADD RES..1
(1500 1400);
FORCEPROP 1 LAST MATERIAL CHIP
J 0
(1500 1250);
DISPLAY 0.617021 (1500 1250);
PAINT SKYBLUE (1500 1250);
FORCEPROP 1 LAST LOCATION R7A12
J 0
(1450 1450);
DISPLAY 0.617021 (1450 1450);
PAINT AQUA (1450 1450);
FORCEPROP 1 LASTPIN (1400 1400) $PN 1
J 0
(1412 1412);
DISPLAY 0.617021 (1412 1412);
PAINT ORANGE (1412 1412);
FORCEPROP 1 LASTPIN (1600 1400) $PN 2
J 0
(1562 1412);
DISPLAY 0.617021 (1562 1412);
PAINT ORANGE (1562 1412);
FORCEPROP 1 LAST PART_NUMBER G21497-005
J 0
(1350 1350);
DISPLAY 0.617021 (1350 1350);
PAINT BLUE (1350 1350);
FORCEPROP 1 LAST WATTAGE 1/16W
J 2
(1475 1250);
DISPLAY 0.617021 (1475 1250);
PAINT SKYBLUE (1475 1250);
FORCEPROP 1 LAST VALUE 0.0
J 2
(1400 1300);
DISPLAY 0.617021 (1400 1300);
PAINT SKYBLUE (1400 1300);
FORCEPROP 1 LAST TOLERANCE 5%
J 0
(1450 1300);
DISPLAY 0.617021 (1450 1300);
PAINT SKYBLUE (1450 1300);
FORCEPROP 1 LAST PACK_TYPE 0402
J 0
(1575 1300);
DISPLAY 0.617021 (1575 1300);
PAINT SKYBLUE (1575 1300);
FORCEPROP 1 LAST PATH I45
J 0
(1450 1550);
DISPLAY 0.978723 (1450 1550);
PAINT WHITE (1450 1550);
DISPLAY INVISIBLE (1450 1550);
FORCEPROP 0 LAST CDS_SEC 1
J 0
(1450 1500);
PAINT MONO (1450 1500);
DISPLAY INVISIBLE (1450 1500);
FORCEPROP 2 LAST CDS_LIB mstr_discrete
J 0
(1500 1400);
PAINT ORANGE (1500 1400);
DISPLAY INVISIBLE (1500 1400);
FORCEPROP 2 LAST SEC_TYPE 0402
J 0
(1450 1600);
DISPLAY 1.021277 (1450 1600);
PAINT ORANGE (1450 1600);
DISPLAY INVISIBLE (1450 1600);
FORCEPROP 2 LAST SEC 1
J 0
(1450 1600);
DISPLAY 0.680851 (1450 1600);
PAINT MONO (1450 1600);
DISPLAY INVISIBLE (1450 1600);
FORCEPROP 2 LAST CDS_LOCATION R7A12
J 0
(1450 1450);
DISPLAY 0.617021 (1450 1450);
PAINT AQUA (1450 1450);
DISPLAY INVISIBLE (1450 1450);
FORCEPROP 2 LAST ROOM VDDQ_DEF_PWR_VR
J 0
(1450 1500);
DISPLAY 1.361702 (1450 1500);
PAINT ORANGE (1450 1500);
DISPLAY INVISIBLE (1450 1500);
FORCEADD RES..1
(1825 1550);
FORCEPROP 1 LAST WATTAGE 1/16W
J 0
(1975 1550);
DISPLAY 0.617021 (1975 1550);
PAINT SKYBLUE (1975 1550);
FORCEPROP 1 LAST PART_NUMBER G21497-005
J 0
(2325 1550);
DISPLAY 0.617021 (2325 1550);
PAINT BLUE (2325 1550);
FORCEPROP 1 LAST VALUE 0.0
J 0
(1525 1550);
DISPLAY 0.617021 (1525 1550);
PAINT SKYBLUE (1525 1550);
FORCEPROP 1 LAST LOCATION R12W29
J 0
(1325 1550);
DISPLAY 0.617021 (1325 1550);
PAINT AQUA (1325 1550);
FORCEPROP 1 LAST TOLERANCE 5%
J 0
(1650 1550);
DISPLAY 0.617021 (1650 1550);
PAINT SKYBLUE (1650 1550);
FORCEPROP 1 LASTPIN (1925 1550) $PN 2
J 0
(1887 1562);
DISPLAY 0.617021 (1887 1562);
PAINT ORANGE (1887 1562);
FORCEPROP 1 LASTPIN (1725 1550) $PN 1
J 0
(1737 1562);
DISPLAY 0.617021 (1737 1562);
PAINT ORANGE (1737 1562);
FORCEPROP 1 LAST MATERIAL EMPTY
J 0
(2175 1550);
DISPLAY 0.617021 (2175 1550);
PAINT RED (2175 1550);
FORCEPROP 1 LAST PACK_TYPE 0402
J 0
(2575 1550);
DISPLAY 0.617021 (2575 1550);
PAINT SKYBLUE (2575 1550);
FORCEPROP 1 LAST PATH I46
J 0
(1775 1700);
DISPLAY 0.978723 (1775 1700);
PAINT WHITE (1775 1700);
DISPLAY INVISIBLE (1775 1700);
FORCEPROP 0 LAST CDS_SEC 1
J 0
(2575 1600);
PAINT MONO (2575 1600);
DISPLAY INVISIBLE (2575 1600);
FORCEPROP 2 LAST CDS_LOCATION R12W29
J 0
(1775 1600);
DISPLAY 0.617021 (1775 1600);
PAINT AQUA (1775 1600);
DISPLAY INVISIBLE (1775 1600);
FORCEPROP 0 LAST BOM_COST MEM_NV
J 0
(1775 1850);
DISPLAY 1.021277 (1775 1850);
PAINT ORANGE (1775 1850);
DISPLAY INVISIBLE (1775 1850);
FORCEPROP 2 LAST SEC_TYPE 0402
J 0
(1775 1750);
DISPLAY 1.021277 (1775 1750);
PAINT ORANGE (1775 1750);
DISPLAY INVISIBLE (1775 1750);
FORCEPROP 0 LAST ROOM NV_DIMM
J 0
(1775 1750);
DISPLAY 1.021277 (1775 1750);
PAINT ORANGE (1775 1750);
DISPLAY INVISIBLE (1775 1750);
FORCEPROP 0 LAST SEC 1
J 0
(1775 1700);
DISPLAY 0.680851 (1775 1700);
PAINT MONO (1775 1700);
DISPLAY INVISIBLE (1775 1700);
FORCEPROP 2 LAST CDS_LIB mstr_discrete
J 0
(1825 1550);
PAINT ORANGE (1825 1550);
DISPLAY INVISIBLE (1825 1550);
FORCEADD OFFPAGE..1
R 2
(2925 75);
FORCEPROP 2 LAST $XR0 218 
J 0
(3111 75);
DISPLAY 0.638298 (3111 75);
PAINT MONO (3111 75);
FORCEPROP 2 LAST PATH I48
J 0
(3125 125);
DISPLAY 1.021277 (3125 125);
PAINT ORANGE (3125 125);
DISPLAY INVISIBLE (3125 125);
FORCEPROP 2 LAST ROOM VDDQ_DEF_PWR_VR
J 0
(2500 150);
DISPLAY 1.361702 (2500 150);
PAINT ORANGE (2500 150);
DISPLAY INVISIBLE (2500 150);
FORCEPROP 1 LAST OFFPAGE TRUE
J 2
(2600 -50);
DISPLAY 1.170213 (2600 -50);
PAINT GREEN (2600 -50);
DISPLAY INVISIBLE (2600 -50);
FORCEPROP 1 LAST COMMENT_BODY TRUE
J 2
(2800 -25);
DISPLAY 1.170213 (2800 -25);
PAINT GREEN (2800 -25);
DISPLAY INVISIBLE (2800 -25);
FORCEPROP 2 LAST CDS_LIB mstr_standard
J 2
(2925 75);
PAINT ORANGE (2925 75);
DISPLAY INVISIBLE (2925 75);
FORCEADD OFFPAGE..2
(2900 1150);
FORCEPROP 2 LAST $XR0 219 
J 0
(3089 1150);
DISPLAY 0.638298 (3089 1150);
PAINT MONO (3089 1150);
FORCEPROP 2 LAST PATH I49
J 0
(3100 1200);
DISPLAY 1.021277 (3100 1200);
PAINT ORANGE (3100 1200);
DISPLAY INVISIBLE (3100 1200);
FORCEPROP 1 LAST OFFPAGE TRUE
J 0
(3225 1025);
DISPLAY 1.170213 (3225 1025);
PAINT GREEN (3225 1025);
DISPLAY INVISIBLE (3225 1025);
FORCEPROP 2 LAST CDS_LIB mstr_standard
J 0
(2900 1150);
PAINT ORANGE (2900 1150);
DISPLAY INVISIBLE (2900 1150);
FORCEPROP 1 LAST COMMENT_BODY TRUE
J 0
(2855 1055);
DISPLAY 1.170213 (2855 1055);
PAINT GREEN (2855 1055);
DISPLAY INVISIBLE (2855 1055);
FORCEPROP 2 LAST ROOM VDDQ_DEF_PWR_VR
J 0
(2475 1225);
DISPLAY 1.361702 (2475 1225);
PAINT ORANGE (2475 1225);
DISPLAY INVISIBLE (2475 1225);
FORCEADD OFFPAGE..1
(-3525 1650);
FORCEPROP 2 LAST $XR0 197 
J 0
(-3777 1650);
DISPLAY 0.638298 (-3777 1650);
PAINT MONO (-3777 1650);
FORCEPROP 2 LAST PATH I5
J 0
(-3775 1700);
DISPLAY 1.021277 (-3775 1700);
PAINT ORANGE (-3775 1700);
DISPLAY INVISIBLE (-3775 1700);
FORCEPROP 2 LAST ROOM VDDQ_DEF_PWR_VR
J 0
(-4075 1725);
DISPLAY 1.361702 (-4075 1725);
PAINT ORANGE (-4075 1725);
DISPLAY INVISIBLE (-4075 1725);
FORCEPROP 2 LAST CDS_LIB mstr_standard
J 0
(-3525 1650);
PAINT ORANGE (-3525 1650);
DISPLAY INVISIBLE (-3525 1650);
FORCEPROP 1 LAST COMMENT_BODY TRUE
J 0
(-3400 1550);
DISPLAY 1.170213 (-3400 1550);
PAINT GREEN (-3400 1550);
DISPLAY INVISIBLE (-3400 1550);
FORCEPROP 1 LAST OFFPAGE TRUE
J 0
(-3200 1525);
DISPLAY 1.170213 (-3200 1525);
PAINT GREEN (-3200 1525);
DISPLAY INVISIBLE (-3200 1525);
FORCEADD OFFPAGE..2
(2900 1200);
FORCEPROP 2 LAST $XR0 219 
J 0
(3089 1200);
DISPLAY 0.638298 (3089 1200);
PAINT MONO (3089 1200);
FORCEPROP 2 LAST PATH I50
J 0
(3100 1250);
DISPLAY 1.021277 (3100 1250);
PAINT ORANGE (3100 1250);
DISPLAY INVISIBLE (3100 1250);
FORCEPROP 1 LAST OFFPAGE TRUE
J 0
(3225 1075);
DISPLAY 1.170213 (3225 1075);
PAINT GREEN (3225 1075);
DISPLAY INVISIBLE (3225 1075);
FORCEPROP 2 LAST CDS_LIB mstr_standard
J 0
(2900 1200);
PAINT ORANGE (2900 1200);
DISPLAY INVISIBLE (2900 1200);
FORCEPROP 1 LAST COMMENT_BODY TRUE
J 0
(2855 1105);
DISPLAY 1.170213 (2855 1105);
PAINT GREEN (2855 1105);
DISPLAY INVISIBLE (2855 1105);
FORCEPROP 2 LAST ROOM VDDQ_DEF_PWR_VR
J 0
(2475 1275);
DISPLAY 1.361702 (2475 1275);
PAINT ORANGE (2475 1275);
DISPLAY INVISIBLE (2475 1275);
FORCEADD OFFPAGE..3
(2875 1400);
FORCEPROP 2 LAST $XR2 215 
J 0
(3299 1400);
DISPLAY 0.638298 (3299 1400);
PAINT MONO (3299 1400);
FORCEPROP 2 LAST $XR1 194 
J 0
(3179 1400);
DISPLAY 0.638298 (3179 1400);
PAINT MONO (3179 1400);
FORCEPROP 2 LAST $XR0 21 
J 0
(3089 1400);
DISPLAY 0.638298 (3089 1400);
PAINT MONO (3089 1400);
FORCEPROP 2 LAST PATH I51
J 0
(3300 1450);
DISPLAY 1.021277 (3300 1450);
PAINT ORANGE (3300 1450);
DISPLAY INVISIBLE (3300 1450);
FORCEPROP 1 LAST OFFPAGE TRUE
J 0
(3200 1275);
DISPLAY 1.170213 (3200 1275);
PAINT GREEN (3200 1275);
DISPLAY INVISIBLE (3200 1275);
FORCEPROP 2 LAST CDS_LIB mstr_standard
J 0
(2875 1400);
PAINT ORANGE (2875 1400);
DISPLAY INVISIBLE (2875 1400);
FORCEPROP 1 LAST COMMENT_BODY TRUE
J 0
(2825 1300);
DISPLAY 1.170213 (2825 1300);
PAINT GREEN (2825 1300);
DISPLAY INVISIBLE (2825 1300);
FORCEPROP 2 LAST ROOM VDDQ_DEF_PWR_VR
J 0
(2475 1475);
DISPLAY 1.361702 (2475 1475);
PAINT ORANGE (2475 1475);
DISPLAY INVISIBLE (2475 1475);
FORCEADD OFFPAGE..2
(2900 1450);
FORCEPROP 2 LAST $XR0 218 
J 0
(3089 1450);
DISPLAY 0.638298 (3089 1450);
PAINT MONO (3089 1450);
FORCEPROP 2 LAST PATH I52
J 0
(3100 1500);
DISPLAY 1.021277 (3100 1500);
PAINT ORANGE (3100 1500);
DISPLAY INVISIBLE (3100 1500);
FORCEPROP 1 LAST OFFPAGE TRUE
J 0
(3225 1325);
DISPLAY 1.170213 (3225 1325);
PAINT GREEN (3225 1325);
DISPLAY INVISIBLE (3225 1325);
FORCEPROP 2 LAST CDS_LIB mstr_standard
J 0
(2900 1450);
PAINT ORANGE (2900 1450);
DISPLAY INVISIBLE (2900 1450);
FORCEPROP 1 LAST COMMENT_BODY TRUE
J 0
(2855 1355);
DISPLAY 1.170213 (2855 1355);
PAINT GREEN (2855 1355);
DISPLAY INVISIBLE (2855 1355);
FORCEPROP 2 LAST ROOM VDDQ_DEF_PWR_VR
J 0
(2475 1525);
DISPLAY 1.361702 (2475 1525);
PAINT ORANGE (2475 1525);
DISPLAY INVISIBLE (2475 1525);
FORCEADD OFFPAGE..3
(2875 1700);
FORCEPROP 2 LAST $XR11 235 
J 0
(3929 1700);
DISPLAY 0.638298 (3929 1700);
PAINT MONO (3929 1700);
FORCEPROP 2 LAST $XR10 226 
J 0
(3809 1700);
DISPLAY 0.638298 (3809 1700);
PAINT MONO (3809 1700);
FORCEPROP 2 LAST $XR9 223 
J 0
(3689 1700);
DISPLAY 0.638298 (3689 1700);
PAINT MONO (3689 1700);
FORCEPROP 2 LAST $XR8 215 
J 0
(3929 1664);
DISPLAY 0.638298 (3929 1664);
PAINT MONO (3929 1664);
FORCEPROP 2 LAST $XR7 213 
J 0
(3809 1664);
DISPLAY 0.638298 (3809 1664);
PAINT MONO (3809 1664);
FORCEPROP 2 LAST $XR6 211 
J 0
(3689 1664);
DISPLAY 0.638298 (3689 1664);
PAINT MONO (3689 1664);
FORCEPROP 2 LAST $XR5 206 
J 0
(3569 1664);
DISPLAY 0.638298 (3569 1664);
PAINT MONO (3569 1664);
FORCEPROP 2 LAST $XR4 201 
J 0
(3449 1664);
DISPLAY 0.638298 (3449 1664);
PAINT MONO (3449 1664);
FORCEPROP 2 LAST $XR3 194 
J 0
(3329 1664);
DISPLAY 0.638298 (3329 1664);
PAINT MONO (3329 1664);
FORCEPROP 2 LAST $XR2 193 
J 0
(3209 1664);
DISPLAY 0.638298 (3209 1664);
PAINT MONO (3209 1664);
FORCEPROP 2 LAST $XR1 159 
J 0
(3089 1664);
DISPLAY 0.638298 (3089 1664);
PAINT MONO (3089 1664);
FORCEPROP 2 LAST $XR0 138 
J 0
(3089 1700);
DISPLAY 0.638298 (3089 1700);
PAINT MONO (3089 1700);
FORCEPROP 2 LAST PATH I53
J 0
(3950 1750);
DISPLAY 1.021277 (3950 1750);
PAINT ORANGE (3950 1750);
DISPLAY INVISIBLE (3950 1750);
FORCEPROP 1 LAST OFFPAGE TRUE
J 0
(3200 1575);
DISPLAY 1.170213 (3200 1575);
PAINT GREEN (3200 1575);
DISPLAY INVISIBLE (3200 1575);
FORCEPROP 2 LAST CDS_LIB mstr_standard
J 0
(2875 1700);
PAINT ORANGE (2875 1700);
DISPLAY INVISIBLE (2875 1700);
FORCEPROP 1 LAST COMMENT_BODY TRUE
J 0
(2825 1600);
DISPLAY 1.170213 (2825 1600);
PAINT GREEN (2825 1600);
DISPLAY INVISIBLE (2825 1600);
FORCEPROP 2 LAST ROOM VDDQ_DEF_PWR_VR
J 0
(2475 1775);
DISPLAY 1.361702 (2475 1775);
PAINT ORANGE (2475 1775);
DISPLAY INVISIBLE (2475 1775);
FORCEADD OFFPAGE..1
R 2
(2875 1750);
FORCEPROP 2 LAST $XR11 226 
J 0
(3541 1714);
DISPLAY 0.638298 (3541 1714);
PAINT MONO (3541 1714);
FORCEPROP 2 LAST $XR10 223 
J 0
(3421 1714);
DISPLAY 0.638298 (3421 1714);
PAINT MONO (3421 1714);
FORCEPROP 2 LAST $XR9 215 
J 0
(3301 1714);
DISPLAY 0.638298 (3301 1714);
PAINT MONO (3301 1714);
FORCEPROP 2 LAST $XR8 206 
J 0
(3181 1714);
DISPLAY 0.638298 (3181 1714);
PAINT MONO (3181 1714);
FORCEPROP 2 LAST $XR7 201 
J 0
(3901 1750);
DISPLAY 0.638298 (3901 1750);
PAINT MONO (3901 1750);
FORCEPROP 2 LAST $XR6 194 
J 0
(3781 1750);
DISPLAY 0.638298 (3781 1750);
PAINT MONO (3781 1750);
FORCEPROP 2 LAST $XR5 193 
J 0
(3661 1750);
DISPLAY 0.638298 (3661 1750);
PAINT MONO (3661 1750);
FORCEPROP 2 LAST $XR4 235 
J 0
(3541 1750);
DISPLAY 0.638298 (3541 1750);
PAINT MONO (3541 1750);
FORCEPROP 2 LAST $XR3 213 
J 0
(3421 1750);
DISPLAY 0.638298 (3421 1750);
PAINT MONO (3421 1750);
FORCEPROP 2 LAST $XR2 211 
J 0
(3301 1750);
DISPLAY 0.638298 (3301 1750);
PAINT MONO (3301 1750);
FORCEPROP 2 LAST $XR1 159 
J 0
(3181 1750);
DISPLAY 0.638298 (3181 1750);
PAINT MONO (3181 1750);
FORCEPROP 2 LAST $XR0 138 
J 0
(3061 1750);
DISPLAY 0.638298 (3061 1750);
PAINT MONO (3061 1750);
FORCEPROP 2 LAST PATH I54
J 0
(3925 1800);
DISPLAY 1.021277 (3925 1800);
PAINT ORANGE (3925 1800);
DISPLAY INVISIBLE (3925 1800);
FORCEPROP 2 LAST CDS_LIB mstr_standard
J 0
(2875 1750);
PAINT ORANGE (2875 1750);
DISPLAY INVISIBLE (2875 1750);
FORCEPROP 1 LAST OFFPAGE TRUE
J 2
(2550 1625);
DISPLAY 1.170213 (2550 1625);
PAINT GREEN (2550 1625);
DISPLAY INVISIBLE (2550 1625);
FORCEPROP 1 LAST COMMENT_BODY TRUE
J 2
(2750 1650);
DISPLAY 1.170213 (2750 1650);
PAINT GREEN (2750 1650);
DISPLAY INVISIBLE (2750 1650);
FORCEPROP 2 LAST ROOM VDDQ_DEF_PWR_VR
J 0
(2450 1825);
DISPLAY 1.361702 (2450 1825);
PAINT ORANGE (2450 1825);
DISPLAY INVISIBLE (2450 1825);
FORCEADD RES..1
(1825 1950);
FORCEPROP 1 LAST MATERIAL EMPTY
J 0
(2125 2050);
DISPLAY 0.617021 (2125 2050);
PAINT RED (2125 2050);
FORCEPROP 1 LAST VALUE 0.0
J 0
(1775 2050);
DISPLAY 0.617021 (1775 2050);
PAINT SKYBLUE (1775 2050);
FORCEPROP 1 LASTPIN (1725 1950) $PN 1
J 0
(1737 1962);
DISPLAY 0.617021 (1737 1962);
PAINT ORANGE (1737 1962);
FORCEPROP 1 LASTPIN (1925 1950) $PN 2
J 0
(1887 1962);
DISPLAY 0.617021 (1887 1962);
PAINT ORANGE (1887 1962);
FORCEPROP 1 LAST LOCATION R12W30
J 0
(1575 2050);
DISPLAY 0.617021 (1575 2050);
PAINT AQUA (1575 2050);
FORCEPROP 1 LAST TOLERANCE 5%
J 0
(1875 2050);
DISPLAY 0.617021 (1875 2050);
PAINT SKYBLUE (1875 2050);
FORCEPROP 1 LAST WATTAGE 1/16W
J 0
(1975 2050);
DISPLAY 0.617021 (1975 2050);
PAINT SKYBLUE (1975 2050);
FORCEPROP 1 LAST PACK_TYPE 0402
J 0
(1825 2000);
DISPLAY 0.617021 (1825 2000);
PAINT SKYBLUE (1825 2000);
FORCEPROP 1 LAST PART_NUMBER G21497-005
J 0
(1575 2000);
DISPLAY 0.617021 (1575 2000);
PAINT BLUE (1575 2000);
FORCEPROP 1 LAST PATH I55
J 0
(1775 2100);
DISPLAY 0.978723 (1775 2100);
PAINT WHITE (1775 2100);
DISPLAY INVISIBLE (1775 2100);
FORCEPROP 0 LAST CDS_SEC 1
J 0
(2125 2100);
PAINT MONO (2125 2100);
DISPLAY INVISIBLE (2125 2100);
FORCEPROP 2 LAST CDS_LOCATION R12W30
J 0
(1775 2000);
DISPLAY 0.617021 (1775 2000);
PAINT AQUA (1775 2000);
DISPLAY INVISIBLE (1775 2000);
FORCEPROP 2 LAST CDS_LIB mstr_discrete
J 0
(1825 1950);
PAINT ORANGE (1825 1950);
DISPLAY INVISIBLE (1825 1950);
FORCEPROP 0 LAST SEC 1
J 0
(1775 2100);
DISPLAY 0.680851 (1775 2100);
PAINT MONO (1775 2100);
DISPLAY INVISIBLE (1775 2100);
FORCEPROP 0 LAST ROOM NV_DIMM
J 0
(1775 2150);
DISPLAY 1.021277 (1775 2150);
PAINT ORANGE (1775 2150);
DISPLAY INVISIBLE (1775 2150);
FORCEPROP 2 LAST SEC_TYPE 0402
J 0
(1775 2150);
DISPLAY 1.021277 (1775 2150);
PAINT ORANGE (1775 2150);
DISPLAY INVISIBLE (1775 2150);
FORCEPROP 0 LAST BOM_COST MEM_NV
J 0
(1775 2250);
DISPLAY 1.021277 (1775 2250);
PAINT ORANGE (1775 2250);
DISPLAY INVISIBLE (1775 2250);
FORCEADD RES..1
(1350 2100);
FORCEPROP 1 LAST VALUE 0.0
J 2
(1325 2050);
DISPLAY 0.617021 (1325 2050);
PAINT SKYBLUE (1325 2050);
FORCEPROP 1 LAST PART_NUMBER G21497-005
J 0
(1125 2000);
DISPLAY 0.617021 (1125 2000);
PAINT BLUE (1125 2000);
FORCEPROP 1 LAST TOLERANCE 5%
J 0
(1350 2050);
DISPLAY 0.617021 (1350 2050);
PAINT SKYBLUE (1350 2050);
FORCEPROP 1 LASTPIN (1450 2100) $PN 2
J 0
(1412 2112);
DISPLAY 0.617021 (1412 2112);
PAINT ORANGE (1412 2112);
FORCEPROP 1 LAST LOCATION R7A11
J 0
(975 2050);
DISPLAY 0.617021 (975 2050);
PAINT AQUA (975 2050);
FORCEPROP 1 LAST WATTAGE 1/16W
J 2
(1250 2050);
DISPLAY 0.617021 (1250 2050);
PAINT SKYBLUE (1250 2050);
FORCEPROP 1 LAST MATERIAL CHIP
J 0
(1000 2000);
DISPLAY 0.617021 (1000 2000);
PAINT SKYBLUE (1000 2000);
FORCEPROP 1 LAST PACK_TYPE 0402
J 0
(1375 2000);
DISPLAY 0.617021 (1375 2000);
PAINT SKYBLUE (1375 2000);
FORCEPROP 1 LASTPIN (1250 2100) $PN 1
J 0
(1262 2112);
DISPLAY 0.617021 (1262 2112);
PAINT ORANGE (1262 2112);
FORCEPROP 1 LAST PATH I56
J 0
(1300 2250);
DISPLAY 0.978723 (1300 2250);
PAINT WHITE (1300 2250);
DISPLAY INVISIBLE (1300 2250);
FORCEPROP 0 LAST CDS_SEC 1
J 0
(1350 2100);
PAINT MONO (1350 2100);
DISPLAY INVISIBLE (1350 2100);
FORCEPROP 2 LAST CDS_LIB mstr_discrete
J 0
(1350 2100);
PAINT ORANGE (1350 2100);
DISPLAY INVISIBLE (1350 2100);
FORCEPROP 2 LAST CDS_LOCATION R7A11
J 0
(1350 2150);
DISPLAY 0.617021 (1350 2150);
PAINT AQUA (1350 2150);
DISPLAY INVISIBLE (1350 2150);
FORCEPROP 2 LAST ROOM VDDQ_DEF_PWR_VR
J 0
(1300 2200);
DISPLAY 1.361702 (1300 2200);
PAINT ORANGE (1300 2200);
DISPLAY INVISIBLE (1300 2200);
FORCEPROP 2 LAST SEC_TYPE 0402
J 0
(1300 2325);
DISPLAY 1.021277 (1300 2325);
PAINT ORANGE (1300 2325);
DISPLAY INVISIBLE (1300 2325);
FORCEPROP 2 LAST SEC 1
J 0
(1300 2325);
DISPLAY 0.680851 (1300 2325);
PAINT MONO (1300 2325);
DISPLAY INVISIBLE (1300 2325);
FORCEADD RES..2
(975 2800);
FORCEPROP 1 LAST MATERIAL CHIP
J 0
(1015 2725);
DISPLAY 0.617021 (1015 2725);
PAINT SKYBLUE (1015 2725);
FORCEPROP 1 LAST PACK_TYPE 0402
J 0
(1015 2625);
DISPLAY 0.617021 (1015 2625);
PAINT SKYBLUE (1015 2625);
FORCEPROP 1 LASTPIN (975 2700) $PN 2
J 0
(980 2710);
DISPLAY 0.617021 (980 2710);
PAINT ORANGE (980 2710);
FORCEPROP 1 LAST PART_NUMBER G21796-026
J 0
(740 2725);
DISPLAY 0.617021 (740 2725);
PAINT BLUE (740 2725);
FORCEPROP 1 LAST WATTAGE 1/16W
J 0
(1015 2775);
DISPLAY 0.617021 (1015 2775);
PAINT SKYBLUE (1015 2775);
FORCEPROP 1 LAST TOLERANCE 1%
J 0
(1020 2825);
DISPLAY 0.617021 (1020 2825);
PAINT SKYBLUE (1020 2825);
FORCEPROP 1 LASTPIN (975 2900) $PN 1
J 0
(980 2862);
DISPLAY 0.617021 (980 2862);
PAINT ORANGE (980 2862);
FORCEPROP 1 LAST VALUE 1.00K
J 0
(1020 2875);
DISPLAY 0.617021 (1020 2875);
PAINT SKYBLUE (1020 2875);
FORCEPROP 1 LAST LOCATION R7B4
J 0
(1020 2925);
DISPLAY 0.617021 (1020 2925);
PAINT AQUA (1020 2925);
FORCEPROP 1 LAST PATH I57
J 0
(1025 2975);
DISPLAY 0.978723 (1025 2975);
PAINT WHITE (1025 2975);
DISPLAY INVISIBLE (1025 2975);
FORCEPROP 0 LAST CDS_SEC 1
J 0
(1025 2975);
PAINT MONO (1025 2975);
DISPLAY INVISIBLE (1025 2975);
FORCEPROP 2 LAST CDS_LIB mstr_discrete
J 0
(975 2800);
PAINT ORANGE (975 2800);
DISPLAY INVISIBLE (975 2800);
FORCEPROP 2 LAST CDS_LOCATION R7B4
J 0
(1020 2925);
DISPLAY 0.617021 (1020 2925);
PAINT AQUA (1020 2925);
DISPLAY INVISIBLE (1020 2925);
FORCEPROP 2 LAST SEC_TYPE 0402
J 0
(1025 3025);
DISPLAY 1.021277 (1025 3025);
PAINT ORANGE (1025 3025);
DISPLAY INVISIBLE (1025 3025);
FORCEPROP 2 LAST SEC 1
J 0
(1025 3025);
DISPLAY 0.680851 (1025 3025);
PAINT MONO (1025 3025);
DISPLAY INVISIBLE (1025 3025);
FORCEPROP 0 LAST ROOM VDDQ_DEF_PWR_VR
J 0
(1025 3025);
DISPLAY 1.021277 (1025 3025);
PAINT ORANGE (1025 3025);
DISPLAY INVISIBLE (1025 3025);
FORCEADD RES..2
(1175 2800);
FORCEPROP 1 LAST MATERIAL CHIP
J 0
(1215 2725);
DISPLAY 0.617021 (1215 2725);
PAINT SKYBLUE (1215 2725);
FORCEPROP 1 LASTPIN (1175 2700) $PN 2
J 0
(1180 2710);
DISPLAY 0.617021 (1180 2710);
PAINT ORANGE (1180 2710);
FORCEPROP 1 LAST LOCATION R7B5
J 0
(1220 2925);
DISPLAY 0.617021 (1220 2925);
PAINT AQUA (1220 2925);
FORCEPROP 1 LAST VALUE 1.00K
J 0
(1220 2875);
DISPLAY 0.617021 (1220 2875);
PAINT SKYBLUE (1220 2875);
FORCEPROP 1 LAST TOLERANCE 1%
J 0
(1220 2825);
DISPLAY 0.617021 (1220 2825);
PAINT SKYBLUE (1220 2825);
FORCEPROP 1 LAST WATTAGE 1/16W
J 0
(1215 2775);
DISPLAY 0.617021 (1215 2775);
PAINT SKYBLUE (1215 2775);
FORCEPROP 1 LASTPIN (1175 2900) $PN 1
J 0
(1180 2862);
DISPLAY 0.617021 (1180 2862);
PAINT ORANGE (1180 2862);
FORCEPROP 1 LAST PACK_TYPE 0402
J 0
(1215 2625);
DISPLAY 0.617021 (1215 2625);
PAINT SKYBLUE (1215 2625);
FORCEPROP 1 LAST PART_NUMBER G21796-026
J 0
(1190 3000);
DISPLAY 0.617021 (1190 3000);
PAINT BLUE (1190 3000);
FORCEPROP 1 LAST PATH I58
J 0
(1225 2975);
DISPLAY 0.978723 (1225 2975);
PAINT WHITE (1225 2975);
DISPLAY INVISIBLE (1225 2975);
FORCEPROP 0 LAST CDS_SEC 1
J 0
(1200 3050);
PAINT MONO (1200 3050);
DISPLAY INVISIBLE (1200 3050);
FORCEPROP 2 LAST CDS_LOCATION R7B5
J 0
(1220 2925);
DISPLAY 0.617021 (1220 2925);
PAINT AQUA (1220 2925);
DISPLAY INVISIBLE (1220 2925);
FORCEPROP 2 LAST CDS_LIB mstr_discrete
J 2
(1175 2800);
PAINT ORANGE (1175 2800);
DISPLAY INVISIBLE (1175 2800);
FORCEPROP 2 LAST ROOM VDDQ_DEF_PWR_VR
J 0
(1225 2975);
DISPLAY 1.361702 (1225 2975);
PAINT ORANGE (1225 2975);
DISPLAY INVISIBLE (1225 2975);
FORCEPROP 2 LAST SEC 1
J 0
(1225 3050);
DISPLAY 0.680851 (1225 3050);
PAINT MONO (1225 3050);
DISPLAY INVISIBLE (1225 3050);
FORCEPROP 2 LAST SEC_TYPE 0402
J 0
(1225 3050);
DISPLAY 1.021277 (1225 3050);
PAINT ORANGE (1225 3050);
DISPLAY INVISIBLE (1225 3050);
FORCEADD RES..1
(1825 2150);
FORCEPROP 1 LAST MATERIAL CHIP
J 0
(2100 2200);
DISPLAY 0.617021 (2100 2200);
PAINT SKYBLUE (2100 2200);
FORCEPROP 1 LASTPIN (1925 2150) $PN 2
J 0
(1887 2162);
DISPLAY 0.787234 (1887 2162);
PAINT ORANGE (1887 2162);
FORCEPROP 1 LAST TOLERANCE 1%
J 0
(1825 2200);
DISPLAY 0.617021 (1825 2200);
PAINT SKYBLUE (1825 2200);
FORCEPROP 1 LAST VALUE 33.2
J 2
(1800 2200);
DISPLAY 0.617021 (1800 2200);
PAINT SKYBLUE (1800 2200);
FORCEPROP 1 LAST PACK_TYPE 0402
J 0
(2450 2200);
DISPLAY 0.617021 (2450 2200);
PAINT SKYBLUE (2450 2200);
FORCEPROP 1 LASTPIN (1725 2150) $PN 1
J 0
(1737 2162);
DISPLAY 0.787234 (1737 2162);
PAINT ORANGE (1737 2162);
FORCEPROP 1 LAST WATTAGE 1/16W
J 2
(2050 2200);
DISPLAY 0.617021 (2050 2200);
PAINT SKYBLUE (2050 2200);
FORCEPROP 1 LAST LOCATION R7B1
J 0
(1600 2200);
DISPLAY 0.617021 (1600 2200);
PAINT AQUA (1600 2200);
FORCEPROP 1 LAST PART_NUMBER G21796-074
J 0
(2225 2200);
DISPLAY 0.617021 (2225 2200);
PAINT BLUE (2225 2200);
FORCEPROP 1 LAST PATH I59
J 0
(1775 2300);
DISPLAY 0.978723 (1775 2300);
PAINT WHITE (1775 2300);
DISPLAY INVISIBLE (1775 2300);
FORCEPROP 0 LAST CDS_SEC 1
J 0
(2450 2250);
PAINT MONO (2450 2250);
DISPLAY INVISIBLE (2450 2250);
FORCEPROP 2 LAST SEC_TYPE 0402
J 0
(1775 2350);
DISPLAY 1.021277 (1775 2350);
PAINT ORANGE (1775 2350);
DISPLAY INVISIBLE (1775 2350);
FORCEPROP 2 LAST SEC 1
J 0
(1775 2350);
PAINT MONO (1775 2350);
DISPLAY INVISIBLE (1775 2350);
FORCEPROP 2 LAST CDS_LOCATION R7B1
J 0
(1775 2200);
DISPLAY 0.617021 (1775 2200);
PAINT AQUA (1775 2200);
DISPLAY INVISIBLE (1775 2200);
FORCEPROP 2 LAST CDS_LIB mstr_discrete
J 0
(1825 2150);
PAINT MONO (1825 2150);
DISPLAY INVISIBLE (1825 2150);
FORCEADD OFFPAGE..1
(-3525 1500);
FORCEPROP 2 LAST $XR0 219 
J 0
(-3777 1500);
DISPLAY 0.638298 (-3777 1500);
PAINT MONO (-3777 1500);
FORCEPROP 2 LAST PATH I6
J 0
(-3775 1550);
DISPLAY 1.021277 (-3775 1550);
PAINT ORANGE (-3775 1550);
DISPLAY INVISIBLE (-3775 1550);
FORCEPROP 2 LAST ROOM VDDQ_DEF_PWR_VR
J 0
(-4075 1575);
DISPLAY 1.361702 (-4075 1575);
PAINT ORANGE (-4075 1575);
DISPLAY INVISIBLE (-4075 1575);
FORCEPROP 1 LAST COMMENT_BODY TRUE
J 0
(-3400 1400);
DISPLAY 1.170213 (-3400 1400);
PAINT GREEN (-3400 1400);
DISPLAY INVISIBLE (-3400 1400);
FORCEPROP 2 LAST CDS_LIB mstr_standard
J 0
(-3525 1500);
PAINT ORANGE (-3525 1500);
DISPLAY INVISIBLE (-3525 1500);
FORCEPROP 1 LAST OFFPAGE TRUE
J 0
(-3200 1375);
DISPLAY 1.170213 (-3200 1375);
PAINT GREEN (-3200 1375);
DISPLAY INVISIBLE (-3200 1375);
FORCEADD RES..1
(1925 2250);
FORCEPROP 1 LAST PART_NUMBER G21796-250
J 0
(1975 2400);
DISPLAY 0.617021 (1975 2400);
PAINT BLUE (1975 2400);
FORCEPROP 1 LAST LOCATION R3M3
J 0
(1875 2350);
DISPLAY 0.617021 (1875 2350);
PAINT AQUA (1875 2350);
FORCEPROP 0 LAST POP NOPOP
J 0
(1850 2275);
DISPLAY 0.638298 (1850 2275);
PAINT RED (1850 2275);
FORCEPROP 1 LAST TOLERANCE 1.0%
J 0
(2100 2300);
DISPLAY 0.617021 (2100 2300);
PAINT SKYBLUE (2100 2300);
FORCEPROP 1 LAST VALUE 22.1
J 2
(1950 2400);
DISPLAY 0.617021 (1950 2400);
PAINT SKYBLUE (1950 2400);
FORCEPROP 1 LAST WATTAGE 1/16W
J 2
(1825 2350);
DISPLAY 0.617021 (1825 2350);
PAINT SKYBLUE (1825 2350);
FORCEPROP 1 LAST MATERIAL CHIP
J 0
(1700 2400);
DISPLAY 0.617021 (1700 2400);
PAINT SKYBLUE (1700 2400);
FORCEPROP 1 LASTPIN (1825 2250) $PN 1
J 0
(1812 2262);
DISPLAY 0.787234 (1812 2262);
PAINT ORANGE (1812 2262);
FORCEPROP 1 LASTPIN (2025 2250) $PN 2
J 0
(2012 2262);
DISPLAY 0.787234 (2012 2262);
PAINT ORANGE (2012 2262);
FORCEPROP 1 LAST PACK_TYPE 0402
J 0
(2000 2350);
DISPLAY 0.617021 (2000 2350);
PAINT SKYBLUE (2000 2350);
FORCEPROP 1 LAST PATH I60
J 0
(1875 2400);
DISPLAY 0.978723 (1875 2400);
PAINT WHITE (1875 2400);
DISPLAY INVISIBLE (1875 2400);
FORCEPROP 0 LAST CDS_SEC 1
J 0
(1900 2425);
PAINT MONO (1900 2425);
DISPLAY INVISIBLE (1900 2425);
FORCEPROP 2 LAST ROOM VDDQ_DEF_PWR_VR
J 0
(1875 2350);
DISPLAY 1.361702 (1875 2350);
PAINT ORANGE (1875 2350);
DISPLAY INVISIBLE (1875 2350);
FORCEPROP 2 LAST CDS_LOCATION R3M3
J 0
(1875 2300);
DISPLAY 0.617021 (1875 2300);
PAINT AQUA (1875 2300);
DISPLAY INVISIBLE (1875 2300);
FORCEPROP 2 LAST CDS_LIB mstr_discrete
J 0
(1925 2250);
PAINT MONO (1925 2250);
DISPLAY INVISIBLE (1925 2250);
FORCEPROP 2 LAST SEC 1
J 0
(1875 2450);
PAINT MONO (1875 2450);
DISPLAY INVISIBLE (1875 2450);
FORCEPROP 2 LAST SEC_TYPE 0402
J 0
(1875 2450);
DISPLAY 1.021277 (1875 2450);
PAINT ORANGE (1875 2450);
DISPLAY INVISIBLE (1875 2450);
FORCEADD OFFPAGE..2
(1675 2500);
FORCEPROP 2 LAST $XR0 222 
J 0
(1864 2500);
DISPLAY 0.638298 (1864 2500);
PAINT MONO (1864 2500);
FORCEPROP 2 LAST PATH I61
J 0
(1875 2550);
DISPLAY 1.021277 (1875 2550);
PAINT ORANGE (1875 2550);
DISPLAY INVISIBLE (1875 2550);
FORCEPROP 2 LAST CDS_LIB mstr_standard
J 0
(1675 2500);
PAINT MONO (1675 2500);
DISPLAY INVISIBLE (1675 2500);
FORCEPROP 2 LAST ROOM VDDQ_ABC_PWR_VR
J 0
(1250 2575);
DISPLAY 1.361702 (1250 2575);
PAINT ORANGE (1250 2575);
DISPLAY INVISIBLE (1250 2575);
FORCEPROP 1 LAST OFFPAGE TRUE
J 0
(2000 2375);
DISPLAY 1.170213 (2000 2375);
PAINT GREEN (2000 2375);
DISPLAY INVISIBLE (2000 2375);
FORCEPROP 1 LAST COMMENT_BODY TRUE
J 0
(1630 2405);
DISPLAY 1.170213 (1630 2405);
PAINT GREEN (1630 2405);
DISPLAY INVISIBLE (1630 2405);
FORCEADD P3V3_STBY..1
(1375 3475);
FORCEPROP 3 LASTPIN (1375 3425) SIG_NAME P3V3_STBY\g
J 0
(1385 3435);
DISPLAY 0.659574 (1385 3435);
PAINT MONO (1385 3435);
DISPLAY INVISIBLE (1385 3435);
FORCEPROP 1 LAST PATH I62
J 0
(1420 3477);
DISPLAY 0.340426 (1420 3477);
PAINT GREEN (1420 3477);
DISPLAY INVISIBLE (1420 3477);
FORCEPROP 1 LAST HDL_POWER P3V3_STBY
J 0
(1075 3350);
DISPLAY 0.872340 (1075 3350);
PAINT ORANGE (1075 3350);
DISPLAY INVISIBLE (1075 3350);
FORCEPROP 1 LAST BODY_TYPE PLUMBING
J 0
(1330 3432);
DISPLAY 0.340426 (1330 3432);
PAINT GREEN (1330 3432);
DISPLAY INVISIBLE (1330 3432);
FORCEPROP 1 LAST VOLTAGE 3.3V
J 0
(1330 3432);
DISPLAY 0.340426 (1330 3432);
PAINT SKYBLUE (1330 3432);
DISPLAY INVISIBLE (1330 3432);
FORCEPROP 2 LAST CDS_LIB mstr_symbols
J 0
(1375 3475);
PAINT ORANGE (1375 3475);
DISPLAY INVISIBLE (1375 3475);
FORCEPROP 1 LAST SIZE 1B
J 0
(1420 3497);
DISPLAY 0.340426 (1420 3497);
PAINT GREEN (1420 3497);
DISPLAY INVISIBLE (1420 3497);
FORCEADD OFFPAGE..2
(2875 2100);
FORCEPROP 2 LAST $XR2 21 
J 0
(3304 2100);
DISPLAY 0.638298 (3304 2100);
PAINT MONO (3304 2100);
FORCEPROP 2 LAST $XR1 215 
J 0
(3184 2100);
DISPLAY 0.638298 (3184 2100);
PAINT MONO (3184 2100);
FORCEPROP 2 LAST $XR0 194 
J 0
(3064 2100);
DISPLAY 0.638298 (3064 2100);
PAINT MONO (3064 2100);
FORCEPROP 2 LAST PATH I64
J 0
(3325 2150);
DISPLAY 1.021277 (3325 2150);
PAINT ORANGE (3325 2150);
DISPLAY INVISIBLE (3325 2150);
FORCEPROP 1 LAST OFFPAGE TRUE
J 0
(3200 1975);
DISPLAY 1.170213 (3200 1975);
PAINT GREEN (3200 1975);
DISPLAY INVISIBLE (3200 1975);
FORCEPROP 2 LAST CDS_LIB mstr_standard
J 0
(2875 2100);
PAINT ORANGE (2875 2100);
DISPLAY INVISIBLE (2875 2100);
FORCEPROP 1 LAST COMMENT_BODY TRUE
J 0
(2830 2005);
DISPLAY 1.170213 (2830 2005);
PAINT GREEN (2830 2005);
DISPLAY INVISIBLE (2830 2005);
FORCEPROP 2 LAST ROOM VDDQ_DEF_PWR_VR
J 0
(2450 2175);
DISPLAY 1.361702 (2450 2175);
PAINT ORANGE (2450 2175);
DISPLAY INVISIBLE (2450 2175);
FORCEADD OFFPAGE..2
(2875 2150);
FORCEPROP 2 LAST $XR2 146 
J 0
(3274 2150);
DISPLAY 0.638298 (3274 2150);
PAINT MONO (3274 2150);
FORCEPROP 2 LAST $XR1 119 
J 0
(3154 2150);
DISPLAY 0.638298 (3154 2150);
PAINT MONO (3154 2150);
FORCEPROP 2 LAST $XR0 94 
J 0
(3064 2150);
DISPLAY 0.638298 (3064 2150);
PAINT MONO (3064 2150);
FORCEPROP 2 LAST PATH I65
J 0
(3275 2200);
DISPLAY 1.021277 (3275 2200);
PAINT ORANGE (3275 2200);
DISPLAY INVISIBLE (3275 2200);
FORCEPROP 1 LAST OFFPAGE TRUE
J 0
(3200 2025);
DISPLAY 1.170213 (3200 2025);
PAINT GREEN (3200 2025);
DISPLAY INVISIBLE (3200 2025);
FORCEPROP 2 LAST CDS_LIB mstr_standard
J 0
(2875 2150);
PAINT ORANGE (2875 2150);
DISPLAY INVISIBLE (2875 2150);
FORCEPROP 1 LAST COMMENT_BODY TRUE
J 0
(2830 2055);
DISPLAY 1.170213 (2830 2055);
PAINT GREEN (2830 2055);
DISPLAY INVISIBLE (2830 2055);
FORCEPROP 2 LAST ROOM VDDQ_DEF_PWR_VR
J 0
(2450 2225);
DISPLAY 1.361702 (2450 2225);
PAINT ORANGE (2450 2225);
DISPLAY INVISIBLE (2450 2225);
FORCEADD OFFPAGE..2
(2875 2250);
FORCEPROP 2 LAST $XR0 197 
J 0
(3064 2250);
DISPLAY 0.638298 (3064 2250);
PAINT MONO (3064 2250);
FORCEPROP 2 LAST PATH I66
J 0
(3075 2300);
DISPLAY 1.021277 (3075 2300);
PAINT ORANGE (3075 2300);
DISPLAY INVISIBLE (3075 2300);
FORCEPROP 1 LAST OFFPAGE TRUE
J 0
(3200 2125);
DISPLAY 1.170213 (3200 2125);
PAINT GREEN (3200 2125);
DISPLAY INVISIBLE (3200 2125);
FORCEPROP 2 LAST CDS_LIB mstr_standard
J 0
(2875 2250);
PAINT ORANGE (2875 2250);
DISPLAY INVISIBLE (2875 2250);
FORCEPROP 1 LAST COMMENT_BODY TRUE
J 0
(2830 2155);
DISPLAY 1.170213 (2830 2155);
PAINT GREEN (2830 2155);
DISPLAY INVISIBLE (2830 2155);
FORCEPROP 2 LAST ROOM VDDQ_DEF_PWR_VR
J 0
(2450 2325);
DISPLAY 1.361702 (2450 2325);
PAINT ORANGE (2450 2325);
DISPLAY INVISIBLE (2450 2325);
FORCEADD RES..2
(2700 2625);
FORCEPROP 1 LAST PART_NUMBER G21796-017
J 0
(2740 2500);
DISPLAY 0.617021 (2740 2500);
PAINT BLUE (2740 2500);
FORCEPROP 1 LAST LOCATION R3L11
J 0
(2745 2750);
DISPLAY 0.617021 (2745 2750);
PAINT AQUA (2745 2750);
FORCEPROP 1 LASTPIN (2700 2525) $PN 2
J 0
(2705 2535);
DISPLAY 0.617021 (2705 2535);
PAINT ORANGE (2705 2535);
FORCEPROP 1 LASTPIN (2700 2725) $PN 1
J 0
(2705 2687);
DISPLAY 0.617021 (2705 2687);
PAINT ORANGE (2705 2687);
FORCEPROP 1 LAST MATERIAL EMPTY
J 0
(2740 2550);
DISPLAY 0.617021 (2740 2550);
PAINT RED (2740 2550);
FORCEPROP 1 LAST WATTAGE 1/16W
J 0
(2740 2600);
DISPLAY 0.617021 (2740 2600);
PAINT SKYBLUE (2740 2600);
FORCEPROP 1 LAST PACK_TYPE 0402
J 0
(2740 2450);
DISPLAY 0.617021 (2740 2450);
PAINT SKYBLUE (2740 2450);
FORCEPROP 1 LAST VALUE 100.0
J 0
(2745 2700);
DISPLAY 0.617021 (2745 2700);
PAINT SKYBLUE (2745 2700);
FORCEPROP 1 LAST TOLERANCE 1%
J 0
(2745 2650);
DISPLAY 0.617021 (2745 2650);
PAINT SKYBLUE (2745 2650);
FORCEPROP 2 LAST SEC_TYPE 0402
J 0
(2750 2875);
DISPLAY 1.021277 (2750 2875);
PAINT ORANGE (2750 2875);
DISPLAY INVISIBLE (2750 2875);
FORCEPROP 2 LAST SEC 1
J 0
(2750 2875);
DISPLAY 0.680851 (2750 2875);
PAINT MONO (2750 2875);
DISPLAY INVISIBLE (2750 2875);
FORCEPROP 2 LAST CDS_LOCATION R3L11
J 0
(2745 2750);
DISPLAY 0.617021 (2745 2750);
PAINT AQUA (2745 2750);
DISPLAY INVISIBLE (2745 2750);
FORCEPROP 2 LAST ROOM VDDQ_DEF_PWR_VR
J 0
(2750 2800);
DISPLAY 1.361702 (2750 2800);
PAINT ORANGE (2750 2800);
DISPLAY INVISIBLE (2750 2800);
FORCEPROP 2 LAST CDS_LIB mstr_discrete
J 0
(2700 2625);
PAINT ORANGE (2700 2625);
DISPLAY INVISIBLE (2700 2625);
FORCEPROP 0 LAST CDS_SEC 1
J 0
(2750 2800);
PAINT MONO (2750 2800);
DISPLAY INVISIBLE (2750 2800);
FORCEPROP 1 LAST PATH I67
J 0
(2750 2800);
DISPLAY 0.978723 (2750 2800);
PAINT WHITE (2750 2800);
DISPLAY INVISIBLE (2750 2800);
FORCEADD PVCCIO_CPU0..1
(2700 2850);
FORCEPROP 3 LASTPIN (2700 2800) SIG_NAME PVCCIO_CPU0\g
J 0
(2710 2810);
DISPLAY 0.659574 (2710 2810);
PAINT MONO (2710 2810);
DISPLAY INVISIBLE (2710 2810);
FORCEPROP 1 LAST VOLTAGE 1.1V
J 0
(2655 2807);
DISPLAY 0.340426 (2655 2807);
PAINT SKYBLUE (2655 2807);
DISPLAY INVISIBLE (2655 2807);
FORCEPROP 2 LAST CDS_LIB mstr_symbols
J 0
(2700 2850);
PAINT ORANGE (2700 2850);
DISPLAY INVISIBLE (2700 2850);
FORCEPROP 1 LAST BODY_TYPE PLUMBING
J 0
(2655 2807);
DISPLAY 0.340426 (2655 2807);
PAINT GREEN (2655 2807);
DISPLAY INVISIBLE (2655 2807);
FORCEPROP 1 LAST HDL_POWER PVCCIO_CPU0
J 1
(2700 2900);
DISPLAY 0.872340 (2700 2900);
PAINT GREEN (2700 2900);
DISPLAY INVISIBLE (2700 2900);
FORCEPROP 1 LAST PATH I68
J 0
(2750 2875);
DISPLAY 0.872340 (2750 2875);
PAINT AQUA (2750 2875);
DISPLAY INVISIBLE (2750 2875);
FORCEADD PXM1310B..2
(150 1500);
FORCEPROP 2 LASTPIN (-300 1750) $PN 26
J 2
(-310 1760);
DISPLAY 0.617021 (-310 1760);
PAINT ORANGE (-310 1760);
FORCEPROP 1 LAST PART_NUMBER H89186-001
J 0
(-250 550);
DISPLAY 0.617021 (-250 550);
PAINT BLUE (-250 550);
FORCEPROP 2 LASTPIN (-300 850) $PN 31
J 2
(-310 860);
DISPLAY 0.617021 (-310 860);
PAINT ORANGE (-310 860);
FORCEPROP 2 LASTPIN (-300 800) $PN 32
J 2
(-310 810);
DISPLAY 0.617021 (-310 810);
PAINT ORANGE (-310 810);
FORCEPROP 2 LASTPIN (-300 700) $PN 36
J 2
(-310 710);
DISPLAY 0.617021 (-310 710);
PAINT ORANGE (-310 710);
FORCEPROP 2 LASTPIN (-300 1050) $PN 30
J 2
(-310 1060);
DISPLAY 0.617021 (-310 1060);
PAINT ORANGE (-310 1060);
FORCEPROP 2 LASTPIN (-300 1350) $PN 19
J 2
(-310 1360);
DISPLAY 0.617021 (-310 1360);
PAINT ORANGE (-310 1360);
FORCEPROP 2 LASTPIN (-300 1650) $PN 37
J 2
(-310 1660);
DISPLAY 0.617021 (-310 1660);
PAINT ORANGE (-310 1660);
FORCEPROP 2 LASTPIN (-300 1600) $PN 38
J 2
(-310 1610);
DISPLAY 0.617021 (-310 1610);
PAINT ORANGE (-310 1610);
FORCEPROP 2 LASTPIN (-300 1500) $PN 35
J 2
(-310 1510);
DISPLAY 0.617021 (-310 1510);
PAINT ORANGE (-310 1510);
FORCEPROP 2 LASTPIN (-300 1450) $PN 34
J 2
(-310 1460);
DISPLAY 0.617021 (-310 1460);
PAINT ORANGE (-310 1460);
FORCEPROP 2 LASTPIN (-300 1300) $PN 29
J 2
(-310 1310);
DISPLAY 0.617021 (-310 1310);
PAINT ORANGE (-310 1310);
FORCEPROP 2 LASTPIN (-300 1200) $PN 10
J 2
(-310 1210);
DISPLAY 0.617021 (-310 1210);
PAINT ORANGE (-310 1210);
FORCEPROP 2 LASTPIN (-300 1100) $PN 20
J 2
(-310 1110);
DISPLAY 0.617021 (-310 1110);
PAINT ORANGE (-310 1110);
FORCEPROP 2 LASTPIN (-300 1800) $PN 24
J 2
(-310 1810);
DISPLAY 0.617021 (-310 1810);
PAINT ORANGE (-310 1810);
FORCEPROP 2 LASTPIN (-300 2250) $PN 39
J 2
(-310 2260);
DISPLAY 0.617021 (-310 2260);
PAINT ORANGE (-310 2260);
FORCEPROP 2 LASTPIN (-300 2150) $PN 15
J 2
(-310 2160);
DISPLAY 0.617021 (-310 2160);
PAINT ORANGE (-310 2160);
FORCEPROP 2 LASTPIN (600 950) $PN 28
J 0
(610 960);
DISPLAY 0.617021 (610 960);
PAINT ORANGE (610 960);
FORCEPROP 2 LASTPIN (600 900) $PN 2
J 0
(610 910);
DISPLAY 0.617021 (610 910);
PAINT ORANGE (610 910);
FORCEPROP 2 LASTPIN (600 2150) $PN 11
J 0
(610 2160);
DISPLAY 0.617021 (610 2160);
PAINT ORANGE (610 2160);
FORCEPROP 2 LASTPIN (600 1750) $PN 7
J 0
(610 1760);
DISPLAY 0.617021 (610 1760);
PAINT ORANGE (610 1760);
FORCEPROP 2 LASTPIN (600 800) $PN 41
J 0
(610 810);
DISPLAY 0.617021 (610 810);
PAINT ORANGE (610 810);
FORCEPROP 2 LASTPIN (600 1200) $PN 5
J 0
(610 1210);
DISPLAY 0.617021 (610 1210);
PAINT ORANGE (610 1210);
FORCEPROP 2 LASTPIN (600 1250) $PN 1
J 0
(610 1260);
DISPLAY 0.617021 (610 1260);
PAINT ORANGE (610 1260);
FORCEPROP 2 LASTPIN (600 1400) $PN 16
J 0
(610 1410);
DISPLAY 0.617021 (610 1410);
PAINT ORANGE (610 1410);
FORCEPROP 2 LASTPIN (600 700) $PN 27
J 0
(610 710);
DISPLAY 0.617021 (610 710);
PAINT ORANGE (610 710);
FORCEPROP 2 LASTPIN (600 1450) $PN 40
J 0
(610 1460);
DISPLAY 0.617021 (610 1460);
PAINT ORANGE (610 1460);
FORCEPROP 2 LASTPIN (600 1150) $PN 4
J 0
(610 1160);
DISPLAY 0.617021 (610 1160);
PAINT ORANGE (610 1160);
FORCEPROP 2 LASTPIN (-300 650) $PN 33
J 2
(-310 660);
DISPLAY 0.617021 (-310 660);
PAINT ORANGE (-310 660);
FORCEPROP 2 LASTPIN (-300 950) $PN 8
J 2
(-310 960);
DISPLAY 0.617021 (-310 960);
PAINT ORANGE (-310 960);
FORCEPROP 2 LASTPIN (600 1100) $PN 3
J 0
(610 1110);
DISPLAY 0.617021 (610 1110);
PAINT ORANGE (610 1110);
FORCEPROP 2 LASTPIN (600 1600) $PN 13
J 0
(610 1610);
DISPLAY 0.617021 (610 1610);
PAINT ORANGE (610 1610);
FORCEPROP 2 LASTPIN (600 1550) $PN 14
J 0
(610 1560);
DISPLAY 0.617021 (610 1560);
PAINT ORANGE (610 1560);
FORCEPROP 2 LASTPIN (600 1850) $PN 12
J 0
(610 1860);
DISPLAY 0.617021 (610 1860);
PAINT ORANGE (610 1860);
FORCEPROP 2 LASTPIN (600 1700) $PN 6
J 0
(610 1710);
DISPLAY 0.617021 (610 1710);
PAINT ORANGE (610 1710);
FORCEPROP 2 LASTPIN (-300 2000) $PN 23
J 2
(-310 2010);
DISPLAY 0.617021 (-310 2010);
PAINT ORANGE (-310 2010);
FORCEPROP 2 LASTPIN (-300 2050) $PN 21
J 2
(-310 2060);
DISPLAY 0.617021 (-310 2060);
PAINT ORANGE (-310 2060);
FORCEPROP 1 LAST LOCATION EU7A5
J 0
(-250 2475);
DISPLAY 0.617021 (-250 2475);
PAINT AQUA (-250 2475);
FORCEPROP 2 LASTPIN (600 2250) $PN 9
J 0
(610 2260);
DISPLAY 0.617021 (610 2260);
PAINT ORANGE (610 2260);
FORCEPROP 2 LASTPIN (600 1950) $PN 18
J 0
(610 1960);
DISPLAY 0.617021 (610 1960);
PAINT ORANGE (610 1960);
FORCEPROP 2 LASTPIN (600 2100) $PN 17
J 0
(610 2110);
DISPLAY 0.617021 (610 2110);
PAINT ORANGE (610 2110);
FORCEPROP 2 LASTPIN (-300 1850) $PN 22
J 2
(-310 1860);
DISPLAY 0.617021 (-310 1860);
PAINT ORANGE (-310 1860);
FORCEPROP 1 LAST MATERIAL IC
J 0
(-250 2425);
DISPLAY 0.617021 (-250 2425);
PAINT SKYBLUE (-250 2425);
FORCEPROP 2 LASTPIN (-300 1950) $PN 25
J 2
(-310 1960);
DISPLAY 0.617021 (-310 1960);
PAINT ORANGE (-310 1960);
FORCEPROP 1 LAST PATH I69
J 0
(250 2426);
PAINT WHITE (250 2426);
DISPLAY INVISIBLE (250 2426);
FORCEPROP 0 LAST CDS_SEC 1
J 0
(-250 2525);
PAINT MONO (-250 2525);
DISPLAY INVISIBLE (-250 2525);
FORCEPROP 2 LAST CDS_LIB mstr_controller
J 0
(150 1500);
PAINT ORANGE (150 1500);
DISPLAY INVISIBLE (150 1500);
FORCEPROP 1 LAST CDS_LMAN_SYM_OUTLINE -400,900,400,-900
J 0
(150 1500);
DISPLAY 0.468085 (150 1500);
PAINT GREEN (150 1500);
DISPLAY INVISIBLE (150 1500);
FORCEPROP 2 LAST CDS_LOCATION EU7A5
J 0
(-250 2475);
PAINT WHITE (-250 2475);
DISPLAY INVISIBLE (-250 2475);
FORCEPROP 1 LAST PACK_TYPE QFN
J 0
(-250 2525);
PAINT SKYBLUE (-250 2525);
DISPLAY INVISIBLE (-250 2525);
FORCEPROP 2 LAST SEC_TYPE QFN
J 0
(-250 2525);
DISPLAY 1.021277 (-250 2525);
PAINT ORANGE (-250 2525);
DISPLAY INVISIBLE (-250 2525);
FORCEPROP 2 LAST SEC 1
J 0
(-250 2525);
DISPLAY 0.680851 (-250 2525);
PAINT MONO (-250 2525);
DISPLAY INVISIBLE (-250 2525);
FORCEADD OFFPAGE..1
(-3525 1600);
FORCEPROP 2 LAST $XR0 197 
J 0
(-3777 1600);
DISPLAY 0.638298 (-3777 1600);
PAINT MONO (-3777 1600);
FORCEPROP 2 LAST PATH I7
J 0
(-3775 1650);
DISPLAY 1.021277 (-3775 1650);
PAINT ORANGE (-3775 1650);
DISPLAY INVISIBLE (-3775 1650);
FORCEPROP 2 LAST ROOM VDDQ_DEF_PWR_VR
J 0
(-4075 1675);
DISPLAY 1.361702 (-4075 1675);
PAINT ORANGE (-4075 1675);
DISPLAY INVISIBLE (-4075 1675);
FORCEPROP 2 LAST CDS_LIB mstr_standard
J 0
(-3525 1600);
PAINT ORANGE (-3525 1600);
DISPLAY INVISIBLE (-3525 1600);
FORCEPROP 1 LAST COMMENT_BODY TRUE
J 0
(-3400 1500);
DISPLAY 1.170213 (-3400 1500);
PAINT GREEN (-3400 1500);
DISPLAY INVISIBLE (-3400 1500);
FORCEPROP 1 LAST OFFPAGE TRUE
J 0
(-3200 1475);
DISPLAY 1.170213 (-3200 1475);
PAINT GREEN (-3200 1475);
DISPLAY INVISIBLE (-3200 1475);
FORCEADD RES..2
(-1900 3250);
FORCEPROP 1 LAST LOCATION R3L13
J 0
(-1855 3375);
DISPLAY 0.617021 (-1855 3375);
PAINT AQUA (-1855 3375);
FORCEPROP 1 LAST VALUE 49.9
J 0
(-1855 3325);
DISPLAY 0.617021 (-1855 3325);
PAINT SKYBLUE (-1855 3325);
FORCEPROP 1 LAST WATTAGE 1/16W
J 0
(-1860 3225);
DISPLAY 0.617021 (-1860 3225);
PAINT SKYBLUE (-1860 3225);
FORCEPROP 1 LAST PART_NUMBER G21796-047
J 0
(-1860 3125);
DISPLAY 0.617021 (-1860 3125);
PAINT BLUE (-1860 3125);
FORCEPROP 1 LASTPIN (-1900 3350) $PN 1
J 0
(-1895 3312);
DISPLAY 0.617021 (-1895 3312);
PAINT ORANGE (-1895 3312);
FORCEPROP 1 LAST TOLERANCE 1%
J 0
(-1855 3275);
DISPLAY 0.617021 (-1855 3275);
PAINT SKYBLUE (-1855 3275);
FORCEPROP 1 LAST MATERIAL EMPTY
J 0
(-1860 3175);
DISPLAY 0.617021 (-1860 3175);
PAINT RED (-1860 3175);
FORCEPROP 1 LAST PACK_TYPE 0402
J 0
(-1860 3075);
DISPLAY 0.617021 (-1860 3075);
PAINT SKYBLUE (-1860 3075);
FORCEPROP 1 LASTPIN (-1900 3150) $PN 2
J 0
(-1895 3160);
DISPLAY 0.617021 (-1895 3160);
PAINT ORANGE (-1895 3160);
FORCEPROP 2 LAST CDS_LOCATION R3L13
J 0
(-1855 3375);
DISPLAY 0.617021 (-1855 3375);
PAINT AQUA (-1855 3375);
DISPLAY INVISIBLE (-1855 3375);
FORCEPROP 1 LAST PATH I70
J 0
(-1850 3425);
DISPLAY 0.978723 (-1850 3425);
PAINT WHITE (-1850 3425);
DISPLAY INVISIBLE (-1850 3425);
FORCEPROP 0 LAST CDS_SEC 1
J 0
(-1850 3425);
PAINT MONO (-1850 3425);
DISPLAY INVISIBLE (-1850 3425);
FORCEPROP 2 LAST CDS_LIB mstr_discrete
J 0
(-1900 3250);
PAINT ORANGE (-1900 3250);
DISPLAY INVISIBLE (-1900 3250);
FORCEPROP 2 LAST ROOM VDDQ_ABC_PWR_VR
J 0
(-1850 3425);
DISPLAY 1.361702 (-1850 3425);
PAINT ORANGE (-1850 3425);
DISPLAY INVISIBLE (-1850 3425);
FORCEPROP 2 LAST SEC 1
J 0
(-1850 3500);
PAINT MONO (-1850 3500);
DISPLAY INVISIBLE (-1850 3500);
FORCEPROP 2 LAST SEC_TYPE 0402
J 0
(-1850 3500);
DISPLAY 1.021277 (-1850 3500);
PAINT ORANGE (-1850 3500);
DISPLAY INVISIBLE (-1850 3500);
FORCEADD RES..2
(-1075 -150);
FORCEPROP 1 LAST PACK_TYPE 0402
J 0
(-1035 -325);
DISPLAY 0.617021 (-1035 -325);
PAINT SKYBLUE (-1035 -325);
FORCEPROP 1 LAST WATTAGE 1/16W
J 0
(-1035 -175);
DISPLAY 0.617021 (-1035 -175);
PAINT SKYBLUE (-1035 -175);
FORCEPROP 1 LAST LOCATION R7A10
J 0
(-1030 -25);
DISPLAY 0.617021 (-1030 -25);
PAINT AQUA (-1030 -25);
FORCEPROP 1 LAST TOLERANCE 1.0%
J 0
(-1030 -125);
DISPLAY 0.617021 (-1030 -125);
PAINT SKYBLUE (-1030 -125);
FORCEPROP 1 LAST PART_NUMBER G21796-317
J 0
(-1035 -275);
DISPLAY 0.617021 (-1035 -275);
PAINT BLUE (-1035 -275);
FORCEPROP 1 LAST VALUE 16K
J 0
(-1030 -75);
DISPLAY 0.617021 (-1030 -75);
PAINT SKYBLUE (-1030 -75);
FORCEPROP 1 LAST MATERIAL CHIP
J 0
(-1035 -225);
DISPLAY 0.617021 (-1035 -225);
PAINT SKYBLUE (-1035 -225);
FORCEPROP 1 LASTPIN (-1075 -250) $PN 2
J 0
(-1070 -240);
DISPLAY 0.617021 (-1070 -240);
PAINT ORANGE (-1070 -240);
FORCEPROP 1 LASTPIN (-1075 -50) $PN 1
J 0
(-1070 -88);
DISPLAY 0.617021 (-1070 -88);
PAINT ORANGE (-1070 -88);
FORCEPROP 0 LAST CDS_LOCATION R7A10
J 0
(-1025 25);
DISPLAY INVISIBLE (-1025 25);
FORCEPROP 1 LAST PATH I73
J 0
(-1025 25);
DISPLAY 0.978723 (-1025 25);
PAINT WHITE (-1025 25);
DISPLAY INVISIBLE (-1025 25);
FORCEPROP 0 LAST CDS_SEC 1
J 0
(-1025 25);
DISPLAY INVISIBLE (-1025 25);
FORCEPROP 2 LAST SEC_TYPE 0402
J 0
(-1025 75);
DISPLAY 1.021277 (-1025 75);
PAINT ORANGE (-1025 75);
DISPLAY INVISIBLE (-1025 75);
FORCEPROP 2 LAST CDS_LIB mstr_discrete
J 0
(-1075 -150);
PAINT ORANGE (-1075 -150);
DISPLAY INVISIBLE (-1075 -150);
FORCEPROP 2 LAST SEC 1
J 0
(-1025 75);
PAINT MONO (-1025 75);
DISPLAY INVISIBLE (-1025 75);
FORCEPROP 0 LAST ROOM VDDQ_ABC_PWR_VR
J 0
(-1025 75);
DISPLAY 1.021277 (-1025 75);
PAINT ORANGE (-1025 75);
DISPLAY INVISIBLE (-1025 75);
FORCEADD RES..2
(-775 -150);
FORCEPROP 1 LAST PART_NUMBER G21796-311
J 0
(-735 -275);
DISPLAY 0.617021 (-735 -275);
PAINT BLUE (-735 -275);
FORCEPROP 1 LAST PACK_TYPE 0402
J 0
(-735 -325);
DISPLAY 0.617021 (-735 -325);
PAINT SKYBLUE (-735 -325);
FORCEPROP 1 LAST WATTAGE 1/16W
J 0
(-735 -175);
DISPLAY 0.617021 (-735 -175);
PAINT SKYBLUE (-735 -175);
FORCEPROP 1 LAST LOCATION R7A8
J 0
(-730 -25);
DISPLAY 0.617021 (-730 -25);
PAINT AQUA (-730 -25);
FORCEPROP 1 LASTPIN (-775 -250) $PN 2
J 0
(-770 -240);
DISPLAY 0.787234 (-770 -240);
PAINT ORANGE (-770 -240);
FORCEPROP 1 LASTPIN (-775 -50) $PN 1
J 0
(-770 -88);
DISPLAY 0.787234 (-770 -88);
PAINT ORANGE (-770 -88);
FORCEPROP 1 LAST VALUE 2.26K
J 0
(-730 -75);
DISPLAY 0.617021 (-730 -75);
PAINT SKYBLUE (-730 -75);
FORCEPROP 1 LAST TOLERANCE 1.0%
J 0
(-730 -125);
DISPLAY 0.617021 (-730 -125);
PAINT SKYBLUE (-730 -125);
FORCEPROP 1 LAST MATERIAL CHIP
J 0
(-735 -225);
DISPLAY 0.617021 (-735 -225);
PAINT SKYBLUE (-735 -225);
FORCEPROP 2 LAST CDS_LOCATION R7A8
J 0
(-730 -25);
DISPLAY 0.617021 (-730 -25);
PAINT AQUA (-730 -25);
DISPLAY INVISIBLE (-730 -25);
FORCEPROP 1 LAST PATH I74
J 0
(-725 25);
DISPLAY 0.978723 (-725 25);
PAINT WHITE (-725 25);
DISPLAY INVISIBLE (-725 25);
FORCEPROP 0 LAST CDS_SEC 1
J 0
(-725 25);
DISPLAY INVISIBLE (-725 25);
FORCEPROP 2 LAST SEC_TYPE 0402
J 0
(-725 75);
DISPLAY 1.021277 (-725 75);
PAINT ORANGE (-725 75);
DISPLAY INVISIBLE (-725 75);
FORCEPROP 2 LAST SEC 1
J 0
(-725 75);
PAINT MONO (-725 75);
DISPLAY INVISIBLE (-725 75);
FORCEPROP 0 LAST BOM_COST SM_CONTROLLER
J 0
(-725 175);
DISPLAY 1.021277 (-725 175);
PAINT ORANGE (-725 175);
DISPLAY INVISIBLE (-725 175);
FORCEPROP 0 LAST ROOM SMBUS
J 0
(-725 75);
DISPLAY 1.021277 (-725 75);
PAINT ORANGE (-725 75);
DISPLAY INVISIBLE (-725 75);
FORCEPROP 0 LAST SKU B
J 0
(-725 75);
DISPLAY 1.021277 (-725 75);
PAINT ORANGE (-725 75);
DISPLAY INVISIBLE (-725 75);
FORCEPROP 2 LAST CDS_LIB mstr_discrete
J 0
(-775 -150);
PAINT ORANGE (-775 -150);
DISPLAY INVISIBLE (-775 -150);
FORCEADD RES..1
(1825 1600);
FORCEPROP 1 LAST LOCATION R12W28
J 0
(1325 1600);
DISPLAY 0.617021 (1325 1600);
PAINT AQUA (1325 1600);
FORCEPROP 1 LAST TOLERANCE 5%
J 0
(2025 1600);
DISPLAY 0.617021 (2025 1600);
PAINT SKYBLUE (2025 1600);
FORCEPROP 1 LASTPIN (1725 1600) $PN 1
J 0
(1737 1612);
DISPLAY 0.617021 (1737 1612);
PAINT WHITE (1737 1612);
FORCEPROP 1 LASTPIN (1925 1600) $PN 2
J 0
(1887 1612);
DISPLAY 0.617021 (1887 1612);
PAINT WHITE (1887 1612);
FORCEPROP 1 LAST PART_NUMBER G21497-005
J 0
(1500 1600);
DISPLAY 0.617021 (1500 1600);
PAINT BLUE (1500 1600);
FORCEPROP 1 LAST VALUE 0.0
J 0
(1950 1600);
DISPLAY 0.617021 (1950 1600);
PAINT SKYBLUE (1950 1600);
FORCEPROP 1 LAST WATTAGE 1/16W
J 0
(2275 1600);
DISPLAY 0.510638 (2275 1600);
PAINT SKYBLUE (2275 1600);
FORCEPROP 1 LAST PACK_TYPE 0402
J 0
(2175 1600);
DISPLAY 0.617021 (2175 1600);
PAINT SKYBLUE (2175 1600);
FORCEPROP 2 LAST CDS_LOCATION R12W28
J 0
(1350 1600);
DISPLAY 0.617021 (1350 1600);
PAINT AQUA (1350 1600);
DISPLAY INVISIBLE (1350 1600);
FORCEPROP 1 LAST PATH I75
J 0
(1775 1750);
DISPLAY 0.978723 (1775 1750);
PAINT WHITE (1775 1750);
DISPLAY INVISIBLE (1775 1750);
FORCEPROP 0 LAST CDS_SEC 1
J 0
(2125 1650);
DISPLAY INVISIBLE (2125 1650);
FORCEPROP 2 LAST CDS_LIB mstr_discrete
J 0
(1825 1600);
DISPLAY 1.340426 (1825 1600);
PAINT ORANGE (1825 1600);
DISPLAY INVISIBLE (1825 1600);
FORCEPROP 2 LAST BOM_COST PROC_SIDEBAND
J 0
(1825 1600);
PAINT MONO (1825 1600);
DISPLAY INVISIBLE (1825 1600);
FORCEPROP 1 LAST MATERIAL CHIP
J 0
(1975 1500);
DISPLAY 0.510638 (1975 1500);
PAINT SKYBLUE (1975 1500);
DISPLAY INVISIBLE (1975 1500);
FORCEPROP 2 LAST ROOM CPU0
J 0
(1775 1750);
PAINT PEACH (1775 1750);
DISPLAY INVISIBLE (1775 1750);
FORCEPROP 2 LAST SEC_TYPE 0402
J 0
(1775 1825);
DISPLAY 1.021277 (1775 1825);
PAINT ORANGE (1775 1825);
DISPLAY INVISIBLE (1775 1825);
FORCEPROP 2 LAST SEC 1
J 0
(1775 1825);
DISPLAY 0.680851 (1775 1825);
PAINT MONO (1775 1825);
DISPLAY INVISIBLE (1775 1825);
FORCEADD RES..2
(2150 2800);
FORCEPROP 1 LAST WATTAGE 1/16W
J 0
(2190 2775);
DISPLAY 0.617021 (2190 2775);
PAINT SKYBLUE (2190 2775);
FORCEPROP 1 LASTPIN (2150 2700) $PN 2
J 0
(2155 2710);
DISPLAY 0.787234 (2155 2710);
PAINT ORANGE (2155 2710);
FORCEPROP 1 LAST PART_NUMBER G21796-311
J 0
(2190 2675);
DISPLAY 0.617021 (2190 2675);
PAINT BLUE (2190 2675);
FORCEPROP 1 LAST MATERIAL CHIP
J 0
(2190 2725);
DISPLAY 0.617021 (2190 2725);
PAINT SKYBLUE (2190 2725);
FORCEPROP 1 LASTPIN (2150 2900) $PN 1
J 0
(2155 2862);
DISPLAY 0.787234 (2155 2862);
PAINT ORANGE (2155 2862);
FORCEPROP 1 LAST PACK_TYPE 0402
J 0
(2190 2625);
DISPLAY 0.617021 (2190 2625);
PAINT SKYBLUE (2190 2625);
FORCEPROP 1 LAST TOLERANCE 1.0%
J 0
(2195 2825);
DISPLAY 0.617021 (2195 2825);
PAINT SKYBLUE (2195 2825);
FORCEPROP 1 LAST VALUE 2.26K
J 0
(2195 2875);
DISPLAY 0.617021 (2195 2875);
PAINT SKYBLUE (2195 2875);
FORCEPROP 1 LAST LOCATION R7A9
J 0
(2195 2925);
DISPLAY 0.617021 (2195 2925);
PAINT AQUA (2195 2925);
FORCEPROP 2 LAST CDS_LOCATION R7A9
J 0
(2195 2925);
DISPLAY 0.617021 (2195 2925);
PAINT AQUA (2195 2925);
DISPLAY INVISIBLE (2195 2925);
FORCEPROP 2 LAST CDS_LIB mstr_discrete
J 0
(2150 2800);
PAINT ORANGE (2150 2800);
DISPLAY INVISIBLE (2150 2800);
FORCEPROP 0 LAST SKU B
J 0
(2200 3025);
DISPLAY 1.021277 (2200 3025);
PAINT ORANGE (2200 3025);
DISPLAY INVISIBLE (2200 3025);
FORCEPROP 0 LAST ROOM SMBUS
J 0
(2200 3025);
DISPLAY 1.021277 (2200 3025);
PAINT ORANGE (2200 3025);
DISPLAY INVISIBLE (2200 3025);
FORCEPROP 0 LAST BOM_COST SM_CONTROLLER
J 0
(2200 3125);
DISPLAY 1.021277 (2200 3125);
PAINT ORANGE (2200 3125);
DISPLAY INVISIBLE (2200 3125);
FORCEPROP 2 LAST SEC 1
J 0
(2200 3025);
PAINT MONO (2200 3025);
DISPLAY INVISIBLE (2200 3025);
FORCEPROP 2 LAST SEC_TYPE 0402
J 0
(2200 3025);
DISPLAY 1.021277 (2200 3025);
PAINT ORANGE (2200 3025);
DISPLAY INVISIBLE (2200 3025);
FORCEPROP 1 LAST PATH I76
J 0
(2200 2975);
DISPLAY 0.978723 (2200 2975);
PAINT WHITE (2200 2975);
DISPLAY INVISIBLE (2200 2975);
FORCEADD OFFPAGE..1
(-3525 1800);
FORCEPROP 2 LAST $XR0 219 
J 0
(-3777 1800);
DISPLAY 0.638298 (-3777 1800);
PAINT MONO (-3777 1800);
FORCEPROP 2 LAST PATH I8
J 0
(-3775 1850);
DISPLAY 1.021277 (-3775 1850);
PAINT ORANGE (-3775 1850);
DISPLAY INVISIBLE (-3775 1850);
FORCEPROP 2 LAST ROOM VDDQ_DEF_PWR_VR
J 0
(-4075 1875);
DISPLAY 1.361702 (-4075 1875);
PAINT ORANGE (-4075 1875);
DISPLAY INVISIBLE (-4075 1875);
FORCEPROP 2 LAST CDS_LIB mstr_standard
J 0
(-3525 1800);
PAINT ORANGE (-3525 1800);
DISPLAY INVISIBLE (-3525 1800);
FORCEPROP 1 LAST COMMENT_BODY TRUE
J 0
(-3400 1700);
DISPLAY 1.170213 (-3400 1700);
PAINT GREEN (-3400 1700);
DISPLAY INVISIBLE (-3400 1700);
FORCEPROP 1 LAST OFFPAGE TRUE
J 0
(-3200 1675);
DISPLAY 1.170213 (-3200 1675);
PAINT GREEN (-3200 1675);
DISPLAY INVISIBLE (-3200 1675);
FORCEADD OFFPAGE..1
(-3525 1850);
FORCEPROP 2 LAST $XR0 219 
J 0
(-3777 1850);
DISPLAY 0.638298 (-3777 1850);
PAINT MONO (-3777 1850);
FORCEPROP 2 LAST PATH I9
J 0
(-3775 1900);
DISPLAY 1.021277 (-3775 1900);
PAINT ORANGE (-3775 1900);
DISPLAY INVISIBLE (-3775 1900);
FORCEPROP 2 LAST CDS_LIB mstr_standard
J 0
(-3525 1850);
PAINT ORANGE (-3525 1850);
DISPLAY INVISIBLE (-3525 1850);
FORCEPROP 1 LAST COMMENT_BODY TRUE
J 0
(-3400 1750);
DISPLAY 1.170213 (-3400 1750);
PAINT GREEN (-3400 1750);
DISPLAY INVISIBLE (-3400 1750);
FORCEPROP 2 LAST ROOM VDDQ_DEF_PWR_VR
J 0
(-4075 1925);
DISPLAY 1.361702 (-4075 1925);
PAINT ORANGE (-4075 1925);
DISPLAY INVISIBLE (-4075 1925);
FORCEPROP 1 LAST OFFPAGE TRUE
J 0
(-3200 1725);
DISPLAY 1.170213 (-3200 1725);
PAINT GREEN (-3200 1725);
DISPLAY INVISIBLE (-3200 1725);
FORCEADD DNS..2
(-1895 3245);
PAINT RED (-1895 3245);
FORCEPROP 1 LAST COMMENT_BODY TRUE
R 1
J 0
(-1820 3020);
DISPLAY 0.872340 (-1820 3020);
PAINT GREEN (-1820 3020);
DISPLAY INVISIBLE (-1820 3020);
FORCEPROP 2 LAST CDS_LIB mstr_misc
J 0
(-1895 3245);
PAINT ORANGE (-1895 3245);
DISPLAY INVISIBLE (-1895 3245);
FORCEADD DESIGN_NOTE..1
(-450 350);
FORCEPROP 0 LAST L1 SMBUS ADDRESS: 0XE4
J 0
(-650 225);
DISPLAY 1.021277 (-650 225);
PAINT RED (-650 225);
FORCEPROP 2 LAST CDS_LIB mstr_symbols
J 0
(-450 350);
PAINT ORANGE (-450 350);
DISPLAY INVISIBLE (-450 350);
FORCEPROP 1 LAST COMMENT_BODY TRUE
J 0
(-425 450);
DISPLAY 0.978723 (-425 450);
PAINT ORANGE (-425 450);
DISPLAY INVISIBLE (-425 450);
FORCEADD DNS..2
(2705 2620);
PAINT RED (2705 2620);
FORCEPROP 2 LAST CDS_LIB mstr_misc
J 0
(2705 2620);
PAINT ORANGE (2705 2620);
DISPLAY INVISIBLE (2705 2620);
FORCEPROP 1 LAST COMMENT_BODY TRUE
R 1
J 0
(2780 2395);
DISPLAY 0.872340 (2780 2395);
PAINT GREEN (2780 2395);
DISPLAY INVISIBLE (2780 2395);
FORCEADD DNS..2
(1830 1495);
PAINT RED (1830 1495);
FORCEPROP 1 LAST COMMENT_BODY TRUE
R 1
J 0
(1905 1270);
DISPLAY 0.872340 (1905 1270);
PAINT GREEN (1905 1270);
DISPLAY INVISIBLE (1905 1270);
FORCEPROP 2 LAST CDS_LIB mstr_misc
J 0
(1830 1495);
PAINT ORANGE (1830 1495);
DISPLAY INVISIBLE (1830 1495);
FORCEADD DESIGN_NOTE..1
(2100 3850);
PAINT PURPLE (2100 3850);
FORCEPROP 0 LAST L1 SVID ADDRESS
J 0
(1905 3715);
DISPLAY 1.021277 (1905 3715);
PAINT VIOLET (1905 3715);
FORCEPROP 0 LAST L2 PVDDQ_DEF: 0X02(BUS #2)
J 0
(1900 3625);
DISPLAY 1.021277 (1900 3625);
PAINT VIOLET (1900 3625);
FORCEPROP 2 LAST CDS_LIB mstr_symbols
J 0
(2100 3850);
PAINT MONO (2100 3850);
DISPLAY INVISIBLE (2100 3850);
FORCEPROP 1 LAST COMMENT_BODY TRUE
J 0
(2125 3950);
DISPLAY 1.319149 (2125 3950);
PAINT GREEN (2125 3950);
DISPLAY INVISIBLE (2125 3950);
FORCEPROP 2 LAST BOM_COST VDDQ_DEF_VR
J 0
(1900 3800);
PAINT MONO (1900 3800);
DISPLAY INVISIBLE (1900 3800);
FORCEPROP 2 LAST ROOM VDDQ_DEF_PWR_VR
J 0
(1900 3800);
PAINT MONO (1900 3800);
DISPLAY INVISIBLE (1900 3800);
FORCEADD INTEL_CORP_BPAGE..1
(4075 -975);
FORCEPROP 1 LAST CDS_CON_LAST_MODIFIED Fri Jun 16 17:49:18 2017
J 0
(2650 -650);
DISPLAY 0.744681 (2650 -650);
PAINT GREEN (2650 -650);
DISPLAY INVISIBLE (2650 -650);
FORCEPROP 1 LAST CUSTOM_TXT_CDS <CURRENT_DESIGN_SHEET> OF <TOTAL_DESIGN_SHEETS>
J 0
(3575 -950);
PAINT ORANGE (3575 -950);
FORCEPROP 1 LAST CUSTOM_TXT_CDS <CON_LAST_MODIFIED>
J 0
(75 -875);
PAINT ORANGE (75 -875);
FORCEPROP 2 LAST CUSTOM_TXT_CDS <XR_PAGE_TITLE>
J 0
(-3815 4275);
DISPLAY 0.638298 (-3815 4275);
PAINT PINK (-3815 4275);
DISPLAY INVISIBLE (-3815 4275);
FORCEPROP 1 LAST SCH_TITLE VDDQ DEF_VR (1 OF 3)
J 0
(-3900 -950);
DISPLAY 1.212766 (-3900 -950);
PAINT ORANGE (-3900 -950);
FORCEPROP 2 LAST PAGE_BORDER TRUE
J 0
(-3815 4275);
DISPLAY 0.638298 (-3815 4275);
PAINT PINK (-3815 4275);
DISPLAY INVISIBLE (-3815 4275);
FORCEPROP 1 LAST COMMENT_BODY TRUE
J 0
(4087 -963);
DISPLAY 0.340426 (4087 -963);
PAINT GREEN (4087 -963);
DISPLAY INVISIBLE (4087 -963);
FORCEPROP 2 LAST CDS_LIB mstr_symbols
J 0
(4075 -975);
DISPLAY 0.744681 (4075 -975);
PAINT ORANGE (4075 -975);
DISPLAY INVISIBLE (4075 -975);
FORCEPROP 2 LAST ROOM VDDQ_DEF_PWR_VR
J 0
(3625 4175);
DISPLAY 0.744681 (3625 4175);
PAINT ORANGE (3625 4175);
DISPLAY INVISIBLE (3625 4175);
FORCEPROP 2 LAST CDS_XR_PAGE_TITLE CR-218 : @BASEBOARD_FAB2_LIB.BASEBOARD_FAB2(SCH_1):PAGE218
J 0
(-3815 4275);
DISPLAY 0.638298 (-3815 4275);
PAINT PINK (-3815 4275);
DISPLAY INVISIBLE (-3815 4275);
FORCEADD DNS..2
(-1145 3220);
PAINT RED (-1145 3220);
FORCEPROP 1 LAST COMMENT_BODY TRUE
R 1
J 0
(-1070 2995);
DISPLAY 0.872340 (-1070 2995);
PAINT GREEN (-1070 2995);
DISPLAY INVISIBLE (-1070 2995);
FORCEPROP 2 LAST CDS_LIB mstr_misc
J 0
(-1145 3220);
PAINT ORANGE (-1145 3220);
DISPLAY INVISIBLE (-1145 3220);
FORCEADD DNS..2
(1830 1970);
PAINT RED (1830 1970);
FORCEPROP 2 LAST CDS_LIB mstr_misc
J 0
(1830 1970);
PAINT ORANGE (1830 1970);
DISPLAY INVISIBLE (1830 1970);
FORCEPROP 1 LAST COMMENT_BODY TRUE
R 1
J 0
(1905 1745);
DISPLAY 0.872340 (1905 1745);
PAINT GREEN (1905 1745);
DISPLAY INVISIBLE (1905 1745);
WIRE 16 -1 (-1250 -200)(-1250 350);
WIRE 16 -1 (-1900 3350)(-1900 3625);
WIRE 16 -1 (-1175 800)(-1175 600);
WIRE 16 -1 (-300 800)(-1175 800);
WIRE 16 -1 (-1075 -350)(-1075 -250);
WIRE 16 -1 (-775 -350)(-775 -250);
WIRE 16 -1 (1950 -250)(1950 -200);
WIRE 16 -1 (2350 -325)(2350 -200);
WIRE 16 -1 (725 575)(725 700);
WIRE 16 -1 (725 800)(725 700);
WIRE 16 -1 (600 700)(725 700);
WIRE 16 -1 (600 800)(725 800);
WIRE 16 -1 (-450 3500)(-450 3600);
WIRE 16 -1 (-1150 3500)(-450 3500);
WIRE 16 -1 (-450 3250)(-450 3500);
WIRE 16 -1 (-1150 3325)(-1150 3500);
WIRE 16 -1 (-150 2650)(-150 2700);
WIRE 16 -1 (250 2650)(250 2700);
WIRE 16 -1 (1625 750)(1625 825);
WIRE 16 -1 (1375 3250)(1375 3425);
WIRE 16 -1 (2150 3250)(1375 3250);
WIRE 16 -1 (1175 3250)(1375 3250);
WIRE 16 -1 (975 3250)(1175 3250);
WIRE 16 -1 (1175 2900)(1175 3250);
WIRE 16 -1 (2150 2900)(2150 3250);
WIRE 16 -1 (975 2900)(975 3250);
WIRE 16 -1 (2700 2725)(2700 2800);
WIRE 3 2175 (-2525 1875)(-1175 1875);
WIRE 3 2175 (-1175 1875)(-1175 2550);
WIRE 3 2175 (-2525 1875)(-2525 2550);
WIRE 3 2175 (-2525 2550)(-1175 2550);
WIRE 16 -1 (1625 2250)(1625 1025);
WIRE 16 -1 (1625 2250)(1825 2250);
WIRE 16 -1 (1525 2500)(1625 2500);
WIRE 16 -1 (1525 2250)(1525 2500);
WIRE 16 -1 (1525 2250)(1625 2250);
WIRE 16 -1 (1175 2250)(1525 2250);
WIRE 16 -1 (1175 2700)(1175 2250);
FORCEPROP 2 LAST SIG_NAME PWRGD_PVDDQ_DEF_R
J 0
(1035 2265);
DISPLAY 0.617021 (1035 2265);
PAINT ORANGE (1035 2265);
WIRE 16 -1 (600 2250)(1175 2250);
WIRE 16 -1 (1950 0)(1950 75);
WIRE 16 -1 (2350 0)(2350 75);
WIRE 16 -1 (2350 75)(1950 75);
FORCEPROP 2 LAST SIG_NAME VR_PVDDQ_DEF_VD12
J 0
(2035 90);
DISPLAY 0.617021 (2035 90);
PAINT ORANGE (2035 90);
WIRE 16 -1 (2350 75)(2875 75);
WIRE 16 2175 (2700 3300)(2700 3800);
WIRE 16 2175 (3850 3300)(2700 3300);
WIRE 16 2175 (3850 3800)(2700 3800);
WIRE 16 2175 (3850 3800)(3850 3300);
WIRE 3 682 (2100 3000)(2100 2600);
WIRE 3 682 (2450 3000)(2100 3000);
WIRE 3 682 (2100 2600)(2450 2600);
WIRE 3 682 (2450 2600)(2450 3000);
WIRE 16 -1 (1450 2100)(2825 2100);
FORCEPROP 2 LAST SIG_NAME SVID_ALERT1_CPU0_R_N
J 0
(2000 2110);
DISPLAY 0.617021 (2000 2110);
PAINT ORANGE (2000 2110);
WIRE 3 682 (2800 1550)(2750 1550);
WIRE 3 682 (2800 1600)(2750 1600);
WIRE 3 682 (2800 1600)(2800 1550);
WIRE 3 682 (2800 1950)(2175 1950);
WIRE 3 682 (2800 1950)(2800 1600);
WIRE 3 682 (2800 1950)(2850 1950);
WIRE 16 -1 (2825 1750)(600 1750);
FORCEPROP 2 LAST SIG_NAME SMB_VR_STBY_LVC3_SCL
J 0
(1685 1765);
DISPLAY 0.617021 (1685 1765);
PAINT ORANGE (1685 1765);
WIRE 16 -1 (1600 1400)(2700 1400);
FORCEPROP 2 LAST SIG_NAME SVID_DIO1_CPU0_R
J 0
(2050 1410);
DISPLAY 0.617021 (2050 1410);
PAINT ORANGE (2050 1410);
WIRE 16 -1 (2700 1400)(2825 1400);
WIRE 16 -1 (2700 2525)(2700 1400);
WIRE 16 -1 (2850 1200)(600 1200);
FORCEPROP 2 LAST SIG_NAME VR_PVDDQ_DEF_PWM1
J 0
(2150 1215);
DISPLAY 0.617021 (2150 1215);
PAINT ORANGE (2150 1215);
WIRE 16 -1 (600 1400)(1400 1400);
FORCEPROP 2 LAST SIG_NAME SVID_VDIO_PVDDQ_DEF
J 0
(700 1415);
DISPLAY 0.617021 (700 1415);
PAINT ORANGE (700 1415);
FORCEPROP 2 LASTPROP $XRERR UNIQUE?
J 0
(460 1415);
DISPLAY 0.638298 (460 1415);
PAINT MONO (460 1415);
DISPLAY INVISIBLE (460 1415);
WIRE 16 -1 (2850 1450)(600 1450);
FORCEPROP 2 LAST SIG_NAME VR_PVDDQ_DEF_VD12
J 0
(2160 1465);
DISPLAY 0.617021 (2160 1465);
PAINT ORANGE (2160 1465);
WIRE 16 -1 (600 1550)(1725 1550);
FORCEPROP 2 LAST SIG_NAME TP_PVDDQ_DEF_MP1
J 0
(700 1565);
DISPLAY 0.617021 (700 1565);
PAINT ORANGE (700 1565);
FORCEPROP 2 LASTPROP $XRERR UNIQUE?
J 0
(460 1565);
DISPLAY 0.638298 (460 1565);
PAINT MONO (460 1565);
DISPLAY INVISIBLE (460 1565);
WIRE 16 -1 (600 1600)(1725 1600);
FORCEPROP 2 LAST SIG_NAME PU_VR_PVDDQ_DEF_FAULT1
J 0
(685 1615);
DISPLAY 0.617021 (685 1615);
PAINT ORANGE (685 1615);
FORCEPROP 2 LASTPROP $XRERR UNIQUE?
J 0
(445 1615);
DISPLAY 0.638298 (445 1615);
PAINT MONO (445 1615);
DISPLAY INVISIBLE (445 1615);
WIRE 16 -1 (2825 1700)(600 1700);
FORCEPROP 2 LAST SIG_NAME SMB_VR_STBY_LVC3_SDA
J 0
(1685 1715);
DISPLAY 0.617021 (1685 1715);
PAINT ORANGE (1685 1715);
WIRE 16 -1 (1725 1950)(600 1950);
FORCEPROP 2 LAST SIG_NAME TP_PVDDQ_DEF_MP2
J 0
(700 1965);
DISPLAY 0.617021 (700 1965);
PAINT ORANGE (700 1965);
FORCEPROP 2 LASTPROP $XRERR UNIQUE?
J 0
(460 1965);
DISPLAY 0.638298 (460 1965);
PAINT MONO (460 1965);
DISPLAY INVISIBLE (460 1965);
WIRE 16 -1 (2125 1550)(1925 1550);
WIRE 16 -1 (1925 1600)(2125 1600);
WIRE 16 -1 (2125 1600)(2125 1550);
WIRE 16 -1 (1925 1950)(2125 1950);
WIRE 16 -1 (2125 1950)(2125 1600);
WIRE 16 -1 (2025 2250)(2125 2250);
WIRE 16 -1 (2125 2250)(2125 1950);
WIRE 16 -1 (2125 2250)(2150 2250);
WIRE 16 -1 (2150 2700)(2150 2250);
WIRE 16 -1 (2150 2250)(2825 2250);
FORCEPROP 2 LAST SIG_NAME PWRGD_PVDDQ_DEF
J 0
(2185 2265);
DISPLAY 0.617021 (2185 2265);
PAINT ORANGE (2185 2265);
WIRE 16 -1 (1250 2100)(600 2100);
FORCEPROP 2 LAST SIG_NAME SVID_ALERT_PVDDQ_DEF
J 0
(700 2115);
DISPLAY 0.617021 (700 2115);
PAINT ORANGE (700 2115);
FORCEPROP 2 LASTPROP $XRERR UNIQUE?
J 0
(460 2115);
DISPLAY 0.638298 (460 2115);
PAINT MONO (460 2115);
DISPLAY INVISIBLE (460 2115);
WIRE 16 -1 (975 2150)(600 2150);
WIRE 16 -1 (975 2700)(975 2150);
WIRE 16 -1 (1725 2150)(975 2150);
FORCEPROP 2 LAST SIG_NAME IRQ_PVDDQ_DEF_VRHOT_LVT3_R_N
J 0
(685 2165);
DISPLAY 0.617021 (685 2165);
PAINT ORANGE (685 2165);
FORCEPROP 2 LASTPROP $XRERR UNIQUE?
J 0
(445 2165);
DISPLAY 0.638298 (445 2165);
PAINT MONO (445 2165);
DISPLAY INVISIBLE (445 2165);
WIRE 16 -1 (-1650 2400)(-1800 2400);
WIRE 16 -1 (-1800 2250)(-1800 2400);
WIRE 16 -1 (-1625 2250)(-1800 2250);
WIRE 16 -1 (-3475 2000)(-1800 2000);
FORCEPROP 2 LAST SIG_NAME VR_PVDDQ_DEF_AIREF2
J 0
(-3465 2015);
DISPLAY 0.617021 (-3465 2015);
PAINT ORANGE (-3465 2015);
WIRE 16 -1 (-1800 2000)(-1800 2250);
WIRE 16 -1 (-300 2000)(-1800 2000);
WIRE 16 -1 (-2800 1200)(-1150 1200);
FORCEPROP 2 LAST SIG_NAME VR_PVDDQ_DEF_VREN
J 0
(-1875 1210);
DISPLAY 0.617021 (-1875 1210);
PAINT ORANGE (-1875 1210);
FORCEPROP 2 LASTPROP $XRERR UNIQUE?
J 0
(-2115 1210);
DISPLAY 0.638298 (-2115 1210);
PAINT MONO (-2115 1210);
DISPLAY INVISIBLE (-2115 1210);
WIRE 16 -1 (-1150 1200)(-300 1200);
WIRE 16 -1 (-1150 1200)(-1150 3125);
WIRE 16 -1 (-1225 1800)(-3475 1800);
FORCEPROP 2 LAST SIG_NAME ISENSE_PVDDQ_DEF_PH2_IMON
J 0
(-3500 1815);
DISPLAY 0.617021 (-3500 1815);
PAINT ORANGE (-3500 1815);
WIRE 16 -1 (-300 1800)(-1225 1800);
WIRE 16 -1 (-1225 1800)(-1225 2250);
WIRE 16 -1 (-1475 2250)(-1225 2250);
WIRE 16 -1 (-1450 2400)(-1225 2400);
WIRE 16 -1 (-1225 2400)(-1225 2250);
WIRE 16 -1 (-625 2150)(-300 2150);
WIRE 16 -1 (-1375 2725)(-625 2725);
FORCEPROP 2 LAST SIG_NAME SVID_CLK_PVDDQ_DEF
J 0
(-1115 2740);
DISPLAY 0.617021 (-1115 2740);
PAINT ORANGE (-1115 2740);
FORCEPROP 2 LASTPROP $XRERR UNIQUE?
J 0
(-1355 2740);
DISPLAY 0.638298 (-1355 2740);
PAINT MONO (-1355 2740);
DISPLAY INVISIBLE (-1355 2740);
WIRE 16 -1 (-625 2725)(-625 2150);
WIRE 16 -1 (-3500 2725)(-1900 2725);
FORCEPROP 0 LAST SIG_NAME SVID_CLK1_CPU0_R
J 0
(-3500 2735);
DISPLAY 0.617021 (-3500 2735);
PAINT ORANGE (-3500 2735);
WIRE 16 -1 (-1900 3150)(-1900 2725);
WIRE 16 -1 (-1575 2725)(-1900 2725);
WIRE 3 682 (-2925 2200)(-2925 2650);
WIRE 3 682 (-2925 2650)(-2600 2650);
WIRE 3 682 (-2600 2200)(-2925 2200);
WIRE 3 682 (-2600 2200)(-2600 2650);
WIRE 16 -1 (-2100 2400)(-1875 2400);
WIRE 16 -1 (-2125 2250)(-1875 2250);
WIRE 16 -1 (-1875 2400)(-1875 2250);
WIRE 16 -1 (-1875 1850)(-3475 1850);
FORCEPROP 2 LAST SIG_NAME ISENSE_PVDDQ_DEF_PH1_IMON
J 0
(-3500 1865);
DISPLAY 0.617021 (-3500 1865);
PAINT ORANGE (-3500 1865);
WIRE 16 -1 (-300 1850)(-1875 1850);
WIRE 16 -1 (-1875 1850)(-1875 2250);
WIRE 16 -1 (-2475 2400)(-2300 2400);
WIRE 16 -1 (-2475 2250)(-2475 2400);
WIRE 16 -1 (-2275 2250)(-2475 2250);
WIRE 16 -1 (-2475 2050)(-2475 2250);
WIRE 16 -1 (-300 2050)(-2475 2050);
WIRE 16 -1 (-3475 2050)(-2475 2050);
FORCEPROP 2 LAST SIG_NAME VR_PVDDQ_DEF_AIREF1
J 0
(-3465 2065);
DISPLAY 0.617021 (-3465 2065);
PAINT ORANGE (-3465 2065);
WIRE 3 2175 (-3700 2350)(-3150 2350);
WIRE 3 2175 (-3150 2350)(-3150 2600);
WIRE 3 2175 (-3700 2350)(-3700 2600);
WIRE 3 2175 (-3700 2600)(-3150 2600);
WIRE 16 -1 (-2650 600)(-3475 600);
FORCEPROP 2 LAST SIG_NAME VSENSE_PVDDQ_DEF_N
J 0
(-3490 615);
DISPLAY 0.617021 (-3490 615);
PAINT ORANGE (-3490 615);
WIRE 16 -1 (-2650 625)(-2650 600);
WIRE 16 -1 (-2125 600)(-2650 600);
WIRE 16 -1 (-2125 1100)(-2125 600);
WIRE 16 -1 (-300 1100)(-2125 1100);
WIRE 3 682 (-1725 450)(-2325 450);
WIRE 3 682 (-1725 0)(-1725 450);
WIRE 3 682 (-2325 450)(-2325 0);
WIRE 3 682 (-2325 0)(-1725 0);
WIRE 16 -1 (-300 1350)(-2175 1350);
WIRE 16 -1 (-2175 875)(-2175 1350);
WIRE 16 -1 (-2650 825)(-2650 875);
WIRE 16 -1 (-2650 875)(-2175 875);
WIRE 16 -1 (-2825 875)(-2650 875);
FORCEPROP 2 LAST SIG_NAME VR_PVDDQ_DEF_AVSP
J 0
(-2690 890);
DISPLAY 0.617021 (-2690 890);
PAINT ORANGE (-2690 890);
FORCEPROP 2 LASTPROP $XRERR UNIQUE?
J 0
(-2930 890);
DISPLAY 0.638298 (-2930 890);
PAINT MONO (-2930 890);
DISPLAY INVISIBLE (-2930 890);
WIRE 16 -1 (-1250 550)(-1250 1500);
WIRE 16 -1 (-1250 1500)(-300 1500);
WIRE 16 -1 (-3475 1500)(-1250 1500);
FORCEPROP 2 LAST SIG_NAME A_TSENSE_PVDDQ_DEF
J 0
(-3500 1515);
DISPLAY 0.617021 (-3500 1515);
PAINT ORANGE (-3500 1515);
WIRE 16 -1 (-3475 1600)(-300 1600);
FORCEPROP 2 LAST SIG_NAME VR_PVDDQ_DEF_AIINSEN
J 0
(-3485 1610);
DISPLAY 0.617021 (-3485 1610);
PAINT ORANGE (-3485 1610);
WIRE 16 -1 (-300 2250)(-450 2250);
WIRE 16 -1 (-450 2950)(-450 2250);
WIRE 16 -1 (-450 3050)(-450 2950);
WIRE 16 -1 (-150 2950)(-450 2950);
WIRE 16 -1 (-150 2900)(-150 2950);
WIRE 16 -1 (250 2950)(-150 2950);
FORCEPROP 2 LAST SIG_NAME VR_PVDDQ_DEF_VDD
J 0
(-190 2965);
DISPLAY 0.617021 (-190 2965);
PAINT ORANGE (-190 2965);
FORCEPROP 2 LASTPROP $XRERR UNIQUE?
J 0
(-430 2965);
DISPLAY 0.638298 (-430 2965);
PAINT MONO (-430 2965);
DISPLAY INVISIBLE (-430 2965);
WIRE 16 -1 (250 2900)(250 2950);
WIRE 3 682 (-1150 -450)(-450 -450);
WIRE 3 682 (-1150 100)(-1150 -450);
WIRE 3 682 (-450 -450)(-450 100);
WIRE 3 682 (-450 100)(-1150 100);
WIRE 16 -1 (-1075 700)(-300 700);
WIRE 16 -1 (-1075 -50)(-1075 700);
FORCEPROP 0 LAST SIG_NAME VR_PVDDQ_DEF_XADDR1
R 1
J 0
(-1085 135);
DISPLAY 0.617021 (-1085 135);
PAINT ORANGE (-1085 135);
FORCEPROP 2 LASTPROP $XRERR UNIQUE?
J 0
(-1325 135);
DISPLAY 0.638298 (-1325 135);
PAINT MONO (-1325 135);
DISPLAY INVISIBLE (-1325 135);
WIRE 16 -1 (-775 650)(-300 650);
WIRE 16 -1 (-775 -50)(-775 650);
FORCEPROP 0 LAST SIG_NAME VR_PVDDQ_DEF_XADDR2
R 1
J 0
(-785 110);
DISPLAY 0.617021 (-785 110);
PAINT ORANGE (-785 110);
FORCEPROP 2 LASTPROP $XRERR UNIQUE?
J 0
(-1025 110);
DISPLAY 0.638298 (-1025 110);
PAINT MONO (-1025 110);
DISPLAY INVISIBLE (-1025 110);
WIRE 16 -1 (-300 1650)(-3475 1650);
FORCEPROP 2 LAST SIG_NAME VR_PVDDQ_DEF_VINSEN
J 0
(-3500 1665);
DISPLAY 0.617021 (-3500 1665);
PAINT ORANGE (-3500 1665);
WIRE 3 682 (-400 850)(-350 850);
WIRE 3 682 (-400 1050)(-400 850);
WIRE 3 682 (-350 1050)(-400 1050);
WIRE 3 682 (-2050 3450)(-2050 3050);
WIRE 3 682 (-1550 3450)(-2050 3450);
WIRE 3 682 (-2050 3050)(-1550 3050);
WIRE 3 682 (-1550 3050)(-1550 3450);
WIRE 16 -1 (-3025 875)(-3500 875);
FORCEPROP 2 LAST SIG_NAME VSENSE_PVDDQ_DEF_P
J 0
(-3515 890);
DISPLAY 0.617021 (-3515 890);
PAINT ORANGE (-3515 890);
WIRE 3 682 (700 900)(650 900);
WIRE 3 682 (700 950)(750 950);
WIRE 3 682 (650 950)(700 950);
WIRE 3 682 (700 950)(700 900);
WIRE 16 -1 (-3000 1200)(-3475 1200);
FORCEPROP 2 LAST SIG_NAME FM_PVDDQ_DEF_EN
J 0
(-3450 1210);
DISPLAY 0.617021 (-3450 1210);
PAINT ORANGE (-3450 1210);
WIRE 3 682 (1350 1800)(1350 1650);
WIRE 3 682 (1550 1800)(1350 1800);
WIRE 3 682 (1350 1650)(1550 1650);
WIRE 3 682 (1550 1650)(1550 1800);
WIRE 16 -1 (600 1150)(2850 1150);
FORCEPROP 2 LAST SIG_NAME VR_PVDDQ_DEF_PWM2
J 0
(2150 1165);
DISPLAY 0.617021 (2150 1165);
PAINT ORANGE (2150 1165);
WIRE 16 -1 (2825 2150)(1925 2150);
FORCEPROP 2 LAST SIG_NAME IRQ_PVDDQ_DEF_VRHOT_LVT3_N
J 0
(1985 2165);
DISPLAY 0.617021 (1985 2165);
PAINT ORANGE (1985 2165);
DOT 1 (1375 3250);
DOT 1 (2700 1400);
DOT 1 (2150 2250);
DOT 1 (2125 2250);
DOT 1 (2800 1600);
DOT 1 (2800 1950);
DOT 1 (1625 2250);
DOT 1 (700 950);
DOT 1 (-2650 600);
DOT 1 (-2650 875);
DOT 1 (-1875 1850);
DOT 1 (-1250 1500);
DOT 1 (-2475 2050);
DOT 1 (-1150 1200);
DOT 1 (725 700);
DOT 1 (-450 2950);
DOT 1 (-450 3500);
DOT 1 (-150 2950);
DOT 1 (2350 75);
DOT 1 (2125 1950);
DOT 1 (975 2150);
DOT 1 (1175 2250);
DOT 1 (1175 3250);
DOT 1 (1525 2250);
DOT 1 (-1225 1800);
DOT 1 (-1875 2250);
DOT 1 (-1800 2000);
DOT 1 (-1800 2250);
DOT 1 (2125 1600);
DOT 1 (-2475 2250);
DOT 1 (-1900 2725);
DOT 1 (-1225 2250);
FORCENOTE
SW FREQ = 833.33KHZ
(2725 3325) 0;
DISPLAY LEFT (2725 3325);
DISPLAY 0.808511 (2725 3325);
PAINT PURPLE (2725 3325);
FORCENOTE
IOUT DI/DT = 15A/US/18.09A/US FOR DS/SS
(2725 3375) 0;
DISPLAY LEFT (2725 3375);
DISPLAY 0.808511 (2725 3375);
PAINT PURPLE (2725 3375);
FORCENOTE
IOUT STEP = 45A/17.96A FOR DS/SS
(2725 3425) 0;
DISPLAY LEFT (2725 3425);
DISPLAY 0.808511 (2725 3425);
PAINT PURPLE (2725 3425);
FORCENOTE
AC & RIPPLE TOL = +/2.8%
(2725 3575) 0;
DISPLAY LEFT (2725 3575);
DISPLAY 0.808511 (2725 3575);
PAINT PURPLE (2725 3575);
FORCENOTE
DC TOL = +/-0.5%
(2725 3625) 0;
DISPLAY LEFT (2725 3625);
DISPLAY 0.808511 (2725 3625);
PAINT PURPLE (2725 3625);
FORCENOTE
RIPPLE GUIDELINE = +/- 0.5%
(2725 3675) 0;
DISPLAY LEFT (2725 3675);
DISPLAY 0.808511 (2725 3675);
PAINT PURPLE (2725 3675);
FORCENOTE
VOUT = 1.2V 
(2725 3725) 0;
DISPLAY LEFT (2725 3725);
DISPLAY 0.808511 (2725 3725);
PAINT PURPLE (2725 3725);
FORCENOTE
IOUT TDC = 65.7A/25.86A FOR DS/SS
(2725 3525) 0;
DISPLAY LEFT (2725 3525);
DISPLAY 0.808511 (2725 3525);
PAINT PURPLE (2725 3525);
FORCENOTE
IOUT PK = 73A/29.38A FOR DS/SS
(2725 3475) 0;
DISPLAY LEFT (2725 3475);
DISPLAY 0.808511 (2725 3475);
PAINT PURPLE (2725 3475);
FORCENOTE
TP FAB3 NOPOP R3M3 0919
(2200 2400) 0;
DISPLAY LEFT (2200 2400);
DISPLAY 0.638298 (2200 2400);
PAINT RED (2200 2400);
FORCENOTE
TP FAB1 NC 0321
(675 1250) 0;
DISPLAY LEFT (675 1250);
DISPLAY 1.021277 (675 1250);
PAINT RED (675 1250);
FORCENOTE
TP FAB1 DEL RES 0314
(1225 1800) 0;
DISPLAY LEFT (1225 1800);
DISPLAY 1.021277 (1225 1800);
PAINT RED (1225 1800);
FORCENOTE
TP FAB3 POP R7A9 1014
(2100 3025) 0;
DISPLAY LEFT (2100 3025);
DISPLAY 0.638298 (2100 3025);
PAINT RED (2100 3025);
FORCENOTE
TP FAB1 NC 0321
(-1050 1925) 0;
DISPLAY LEFT (-1050 1925);
DISPLAY 1.021277 (-1050 1925);
PAINT RED (-1050 1925);
FORCENOTE
TP FAB1 CO-LAY WITH FAIRCHILD PARTS 1203
(-2487 1931) 0;
DISPLAY LEFT (-2487 1931);
DISPLAY 0.851064 (-2487 1931);
PAINT RED (-2487 1931);
FORCENOTE
TP FAB4 NOPOP RF18 AND CF18 FOR SS BOM 20170124
(-2525 2550) 0;
DISPLAY LEFT (-2525 2550);
DISPLAY 0.638298 (-2525 2550);
PAINT RED (-2525 2550);
FORCENOTE
TP FAB1 NC 0321
(-1050 1725) 0;
DISPLAY LEFT (-1050 1725);
DISPLAY 1.021277 (-1050 1725);
PAINT RED (-1050 1725);
FORCENOTE
TP FAB1 ADD RES 0303
(2900 1950) 0;
DISPLAY LEFT (2900 1950);
DISPLAY 0.638298 (2900 1950);
PAINT RED (2900 1950);
FORCENOTE
TP FAB3 POP R12W28 0919
(2900 1900) 0;
DISPLAY LEFT (2900 1900);
DISPLAY 0.638298 (2900 1900);
PAINT RED (2900 1900);
FORCENOTE
TP FAB1 NOPOP RES 0316
(-2225 3475) 0;
DISPLAY LEFT (-2225 3475);
DISPLAY 1.021277 (-2225 3475);
PAINT RED (-2225 3475);
FORCENOTE
TP FAB1 NC 0321
(-1050 1275) 0;
DISPLAY LEFT (-1050 1275);
DISPLAY 1.021277 (-1050 1275);
PAINT RED (-1050 1275);
FORCENOTE
TP FAB1 NC 0321
(-1050 975) 0;
DISPLAY LEFT (-1050 975);
DISPLAY 1.021277 (-1050 975);
PAINT RED (-1050 975);
FORCENOTE
TP FAB3 CHANGE RES 0804
(-1150 -600) 0;
DISPLAY LEFT (-1150 -600);
DISPLAY 0.638298 (-1150 -600);
PAINT RED (-1150 -600);
FORCENOTE
TP FAB1 CHANGE R7A10 RES 0523
(-1150 -550) 0;
DISPLAY LEFT (-1150 -550);
DISPLAY 0.638298 (-1150 -550);
PAINT RED (-1150 -550);
FORCENOTE
TP FAB1 CHANGE R7A10 RES AND NOPOP R7A8 0408
(-1150 -500) 0;
DISPLAY LEFT (-1150 -500);
DISPLAY 0.638298 (-1150 -500);
PAINT RED (-1150 -500);
FORCENOTE
TP FAB1 NC 0321
(675 1075) 0;
DISPLAY LEFT (675 1075);
DISPLAY 1.021277 (675 1075);
PAINT RED (675 1075);
FORCENOTE
TP FAB1 NC 0321
(675 1850) 0;
DISPLAY LEFT (675 1850);
DISPLAY 1.021277 (675 1850);
PAINT RED (675 1850);
FORCENOTE
TP FAB1 DEL NETS 0309
(825 950) 0;
DISPLAY LEFT (825 950);
DISPLAY 1.021277 (825 950);
PAINT RED (825 950);
FORCENOTE
TP FAB1 DELETE RES 0203
(-2925 2675) 0;
DISPLAY LEFT (-2925 2675);
DISPLAY 0.638298 (-2925 2675);
PAINT RED (-2925 2675);
FORCENOTE
ROOM=VDDQ_DEF_PWR_VR
(-3905 -815) 0;
DISPLAY LEFT (-3905 -815);
DISPLAY 2.446809 (-3905 -815);
PAINT PURPLE (-3905 -815);
FORCENOTE
TP FAB1 DEL CAP 0218
(-2350 -75) 0;
DISPLAY LEFT (-2350 -75);
DISPLAY 1.021277 (-2350 -75);
PAINT RED (-2350 -75);
FORCENOTE
TP FAB1 NC 0321
(-1050 1425) 0;
DISPLAY LEFT (-1050 1425);
DISPLAY 1.021277 (-1050 1425);
PAINT RED (-1050 1425);
FORCENOTE
RF17&RF18
(-3675 2525) 0;
DISPLAY LEFT (-3675 2525);
DISPLAY 0.872340 (-3675 2525);
PAINT RED (-3675 2525);
FORCENOTE
FAIRCHILD:POP
(-3675 2375) 0;
DISPLAY LEFT (-3675 2375);
DISPLAY 0.872340 (-3675 2375);
PAINT RED (-3675 2375);
FORCENOTE
INFINEON:NOPOP
(-3675 2425) 0;
DISPLAY LEFT (-3675 2425);
DISPLAY 0.872340 (-3675 2425);
PAINT RED (-3675 2425);
FORCENOTE
CF17&CF18
(-3675 2475) 0;
DISPLAY LEFT (-3675 2475);
DISPLAY 0.872340 (-3675 2475);
PAINT RED (-3675 2475);
FORCENOTE
TP FAB4 CHANGE RF17 TO 953OHM FOR VR FAILCHILD, SINGLE SIDE BOM 20170123
(-2525 2600) 0;
DISPLAY LEFT (-2525 2600);
DISPLAY 0.638298 (-2525 2600);
PAINT RED (-2525 2600);
QUIT
